FILE_TYPE = MACRO_DRAWING;
SET COLOR_WIRE YELLOW;
SET COLOR_PROP MONO;
SET COLOR_DOT WHITE;
SET COLOR_ARC YELLOW;
SET COLOR_BODY GREEN;
SET COLOR_NOTE MONO;
SET PROP_DISPLAY VALUE;
SET PAGE_NUMBER P239;
FORCEADD CAP..1
(10875 3625);
FORCEPROP 1 LASTPIN (10875 3725) $PN 1
J 0
(10885 3705);
DISPLAY 0.617021 (10885 3705);
PAINT WHITE (10885 3705);
FORCEPROP 1 LASTPIN (10875 3525) $PN 2
J 0
(10885 3505);
DISPLAY 0.617021 (10885 3505);
PAINT WHITE (10885 3505);
FORCEPROP 1 LAST TOLERANCE 20%
J 0
(10925 3575);
DISPLAY 0.617021 (10925 3575);
PAINT SKYBLUE (10925 3575);
FORCEPROP 1 LAST PACK_TYPE 0603
J 0
(10925 3425);
DISPLAY 0.617021 (10925 3425);
PAINT SKYBLUE (10925 3425);
FORCEPROP 1 LAST VALUE 10UF
J 0
(10925 3675);
DISPLAY 0.617021 (10925 3675);
PAINT SKYBLUE (10925 3675);
FORCEPROP 1 LAST MATERIAL X6S
J 0
(10925 3525);
DISPLAY 0.617021 (10925 3525);
PAINT SKYBLUE (10925 3525);
FORCEPROP 1 LAST PART_NUMBER E15431-002
J 0
(10925 3475);
DISPLAY 0.617021 (10925 3475);
PAINT BLUE (10925 3475);
FORCEPROP 1 LAST VOLTAGE 6.3V
J 0
(10925 3625);
DISPLAY 0.617021 (10925 3625);
PAINT SKYBLUE (10925 3625);
FORCEPROP 1 LAST LOCATION C1T15
J 0
(10925 3725);
DISPLAY 0.617021 (10925 3725);
PAINT AQUA (10925 3725);
FORCEPROP 2 LAST CDS_LOCATION C1T15
J 0
(10925 3725);
DISPLAY 0.617021 (10925 3725);
PAINT AQUA (10925 3725);
DISPLAY INVISIBLE (10925 3725);
FORCEPROP 2 LAST CDS_LIB mstr_discrete
J 0
(10875 3625);
PAINT ORANGE (10875 3625);
DISPLAY INVISIBLE (10875 3625);
FORCEPROP 2 LAST SEC 1
J 0
(10925 3825);
DISPLAY 1.106383 (10925 3825);
PAINT MONO (10925 3825);
DISPLAY INVISIBLE (10925 3825);
FORCEPROP 2 LAST SEC_TYPE 0603
J 0
(10925 3825);
DISPLAY 1.659574 (10925 3825);
PAINT ORANGE (10925 3825);
DISPLAY INVISIBLE (10925 3825);
FORCEPROP 1 LAST PATH I12
J 0
(10925 3775);
DISPLAY 0.978723 (10925 3775);
PAINT WHITE (10925 3775);
DISPLAY INVISIBLE (10925 3775);
FORCEPROP 2 LAST ROOM P1V538_BMC_STBY_VR
J 0
(10925 3825);
PAINT GREEN (10925 3825);
DISPLAY INVISIBLE (10925 3825);
FORCEPROP 2 LAST BOM_COST P1V538_BMC_STBY_VR
J 0
(10925 3775);
PAINT WHITE (10925 3775);
DISPLAY INVISIBLE (10925 3775);
FORCEADD RES..1
R 1
(10350 3125);
FORCEPROP 1 LAST LOCATION R9F32
J 0
(10425 3150);
DISPLAY 0.617021 (10425 3150);
PAINT AQUA (10425 3150);
FORCEPROP 1 LASTPIN (10350 3225) $PN 2
J 0
(10388 3187);
DISPLAY 0.617021 (10388 3187);
PAINT ORANGE (10388 3187);
FORCEPROP 1 LASTPIN (10350 3025) $PN 1
J 0
(10388 3037);
DISPLAY 0.617021 (10388 3037);
PAINT ORANGE (10388 3037);
FORCEPROP 1 LAST WATTAGE 1/16W
J 2
(10825 3050);
DISPLAY 0.617021 (10825 3050);
PAINT SKYBLUE (10825 3050);
FORCEPROP 1 LAST PART_NUMBER G21796-221
J 0
(10425 3000);
DISPLAY 0.617021 (10425 3000);
PAINT BLUE (10425 3000);
FORCEPROP 2 LAST P1V5_STBY_IBMC 
J 0
(10400 3375);
PAINT GREEN (10400 3375);
FORCEPROP 2 LAST P1V5_STBY_IBMC_VR 
J 0
(10400 3325);
PAINT GREEN (10400 3325);
FORCEPROP 1 LAST VALUE 13K
J 2
(10500 3100);
DISPLAY 0.617021 (10500 3100);
PAINT SKYBLUE (10500 3100);
FORCEPROP 1 LAST TOLERANCE 1.0%
J 0
(10550 3050);
DISPLAY 0.617021 (10550 3050);
PAINT SKYBLUE (10550 3050);
FORCEPROP 1 LAST MATERIAL CHIP
J 0
(10425 3050);
DISPLAY 0.617021 (10425 3050);
PAINT SKYBLUE (10425 3050);
FORCEPROP 1 LAST PACK_TYPE 0402
J 0
(10450 2950);
DISPLAY 0.617021 (10450 2950);
PAINT SKYBLUE (10450 2950);
FORCEPROP 2 LAST SEC_TYPE 0402
J 0
(10400 3425);
DISPLAY 1.021277 (10400 3425);
PAINT ORANGE (10400 3425);
DISPLAY INVISIBLE (10400 3425);
FORCEPROP 2 LAST BOM_COST P1V538_BMC_STBY_VR
J 0
(10400 3425);
PAINT WHITE (10400 3425);
DISPLAY INVISIBLE (10400 3425);
FORCEPROP 2 LAST SEC 1
J 0
(10400 3425);
DISPLAY 0.680851 (10400 3425);
PAINT MONO (10400 3425);
DISPLAY INVISIBLE (10400 3425);
FORCEPROP 2 LAST CDS_LOCATION R9F32
J 0
(10425 3150);
DISPLAY 0.617021 (10425 3150);
PAINT AQUA (10425 3150);
DISPLAY INVISIBLE (10425 3150);
FORCEPROP 2 LAST ROOM P1V538_BMC_STBY_VR
J 0
(10400 3275);
PAINT GREEN (10400 3275);
DISPLAY INVISIBLE (10400 3275);
FORCEPROP 2 LAST CDS_LIB mstr_discrete
J 0
(10350 3125);
PAINT MONO (10350 3125);
DISPLAY INVISIBLE (10350 3125);
FORCEPROP 1 LAST PATH I15
R 1
J 0
(10200 3075);
DISPLAY 0.978723 (10200 3075);
PAINT WHITE (10200 3075);
DISPLAY INVISIBLE (10200 3075);
FORCEADD GND..1
(10350 2900);
FORCEPROP 3 LASTPIN (10350 2950) SIG_NAME GND\g
J 0
(10360 2960);
DISPLAY 0.659574 (10360 2960);
PAINT MONO (10360 2960);
DISPLAY INVISIBLE (10360 2960);
FORCEPROP 2 LAST P1V5_STBY_IBMC 
J 0
(10375 3025);
PAINT GREEN (10375 3025);
FORCEPROP 2 LAST P1V5_STBY_IBMC_VR 
J 0
(10375 2975);
PAINT GREEN (10375 2975);
FORCEPROP 1 LAST PATH I16
J 0
(10425 2900);
DISPLAY 0.872340 (10425 2900);
PAINT AQUA (10425 2900);
DISPLAY INVISIBLE (10425 2900);
FORCEPROP 2 LAST BOM_COST P1V538_BMC_STBY_VR
J 0
(10375 3075);
PAINT WHITE (10375 3075);
DISPLAY INVISIBLE (10375 3075);
FORCEPROP 2 LAST CDS_LIB mstr_symbols
J 0
(10350 2900);
PAINT ORANGE (10350 2900);
DISPLAY INVISIBLE (10350 2900);
FORCEPROP 1 LAST SIZE 1B
J 0
(10425 2850);
DISPLAY 0.872340 (10425 2850);
PAINT ORANGE (10425 2850);
DISPLAY INVISIBLE (10425 2850);
FORCEPROP 1 LAST VOLTAGE 0.0V
J 0
(10305 2857);
DISPLAY 0.340426 (10305 2857);
PAINT SKYBLUE (10305 2857);
DISPLAY INVISIBLE (10305 2857);
FORCEPROP 2 LAST ROOM P1V538_BMC_STBY_VR
J 0
(10000 2975);
DISPLAY 0.872340 (10000 2975);
PAINT GREEN (10000 2975);
DISPLAY INVISIBLE (10000 2975);
FORCEPROP 1 LAST BODY_TYPE PLUMBING
J 0
(10305 2857);
DISPLAY 0.340426 (10305 2857);
PAINT GREEN (10305 2857);
DISPLAY INVISIBLE (10305 2857);
FORCEPROP 1 LAST HDL_POWER GND
J 0
(10350 3050);
DISPLAY 0.872340 (10350 3050);
PAINT GREEN (10350 3050);
DISPLAY INVISIBLE (10350 3050);
FORCEADD CAP..1
(6525 4150);
FORCEPROP 1 LASTPIN (6525 4250) $PN 1
J 0
(6535 4230);
DISPLAY 0.617021 (6535 4230);
PAINT WHITE (6535 4230);
FORCEPROP 1 LASTPIN (6525 4050) $PN 2
J 0
(6535 4030);
DISPLAY 0.617021 (6535 4030);
PAINT WHITE (6535 4030);
FORCEPROP 1 LAST LOCATION C1T7
J 0
(6575 4250);
DISPLAY 0.617021 (6575 4250);
PAINT AQUA (6575 4250);
FORCEPROP 1 LAST VALUE 10UF
J 0
(6575 4200);
DISPLAY 0.617021 (6575 4200);
PAINT SKYBLUE (6575 4200);
FORCEPROP 1 LAST VOLTAGE 6.3V
J 0
(6575 4150);
DISPLAY 0.617021 (6575 4150);
PAINT SKYBLUE (6575 4150);
FORCEPROP 1 LAST TOLERANCE 20%
J 0
(6575 4100);
DISPLAY 0.617021 (6575 4100);
PAINT SKYBLUE (6575 4100);
FORCEPROP 1 LAST PART_NUMBER E15431-002
J 0
(6575 4000);
DISPLAY 0.617021 (6575 4000);
PAINT BLUE (6575 4000);
FORCEPROP 1 LAST PACK_TYPE 0603
J 0
(6575 3950);
DISPLAY 0.617021 (6575 3950);
PAINT SKYBLUE (6575 3950);
FORCEPROP 1 LAST MATERIAL X6S
J 0
(6575 4050);
DISPLAY 0.617021 (6575 4050);
PAINT SKYBLUE (6575 4050);
FORCEPROP 2 LAST CDS_LIB mstr_discrete
J 0
(6525 4150);
PAINT ORANGE (6525 4150);
DISPLAY INVISIBLE (6525 4150);
FORCEPROP 2 LAST CDS_LOCATION C1T7
J 0
(6575 4250);
DISPLAY 0.617021 (6575 4250);
PAINT AQUA (6575 4250);
DISPLAY INVISIBLE (6575 4250);
FORCEPROP 2 LAST SEC 1
J 0
(6575 4350);
DISPLAY 1.106383 (6575 4350);
PAINT MONO (6575 4350);
DISPLAY INVISIBLE (6575 4350);
FORCEPROP 2 LAST SEC_TYPE 0603
J 0
(6575 4350);
DISPLAY 1.659574 (6575 4350);
PAINT ORANGE (6575 4350);
DISPLAY INVISIBLE (6575 4350);
FORCEPROP 1 LAST PATH I22
J 0
(6575 4300);
DISPLAY 0.978723 (6575 4300);
PAINT WHITE (6575 4300);
DISPLAY INVISIBLE (6575 4300);
FORCEPROP 2 LAST ROOM P1V538_BMC_STBY_VR
J 0
(6575 4300);
DISPLAY 0.723404 (6575 4300);
PAINT GREEN (6575 4300);
DISPLAY INVISIBLE (6575 4300);
FORCEPROP 2 LAST BOM_COST P1V538_BMC_STBY_VR
J 0
(6400 4300);
PAINT WHITE (6400 4300);
DISPLAY INVISIBLE (6400 4300);
FORCEADD CAP..1
R 2
(7050 3300);
FORCEPROP 1 LASTPIN (7050 3400) $PN 1
J 2
(7040 3380);
DISPLAY 0.617021 (7040 3380);
PAINT WHITE (7040 3380);
FORCEPROP 1 LASTPIN (7050 3200) $PN 2
J 2
(7040 3180);
DISPLAY 0.617021 (7040 3180);
PAINT WHITE (7040 3180);
FORCEPROP 1 LAST TOLERANCE 10%
J 2
(7000 3250);
DISPLAY 0.617021 (7000 3250);
PAINT SKYBLUE (7000 3250);
FORCEPROP 1 LAST VOLTAGE 50V
J 2
(7000 3300);
DISPLAY 0.617021 (7000 3300);
PAINT SKYBLUE (7000 3300);
FORCEPROP 1 LAST LOCATION C9F6
J 2
(6875 3375);
DISPLAY 0.617021 (6875 3375);
PAINT AQUA (6875 3375);
FORCEPROP 1 LAST VALUE 1000PF
J 2
(6900 3325);
DISPLAY 0.617021 (6900 3325);
PAINT SKYBLUE (6900 3325);
FORCEPROP 1 LAST MATERIAL EMPTY
J 2
(7000 3200);
DISPLAY 0.617021 (7000 3200);
PAINT RED (7000 3200);
FORCEPROP 1 LAST PACK_TYPE 0402LF
J 2
(6875 3250);
DISPLAY 0.617021 (6875 3250);
PAINT SKYBLUE (6875 3250);
FORCEPROP 1 LAST PART_NUMBER A36096-046
J 2
(7000 3150);
DISPLAY 0.617021 (7000 3150);
PAINT BLUE (7000 3150);
FORCEPROP 2 LAST CDS_SEC 1
J 0
(7010 3510);
DISPLAY 1.617021 (7010 3510);
PAINT MONO (7010 3510);
DISPLAY INVISIBLE (7010 3510);
FORCEPROP 2 LAST CDS_LIB mstr_discrete
J 0
(7050 3300);
DISPLAY 1.617021 (7050 3300);
PAINT MONO (7050 3300);
DISPLAY INVISIBLE (7050 3300);
FORCEPROP 2 LAST CDS_LOCATION C9F6
J 2
(6875 3375);
DISPLAY 0.617021 (6875 3375);
PAINT AQUA (6875 3375);
DISPLAY INVISIBLE (6875 3375);
FORCEPROP 2 LAST $SEC 1
J 0
(7010 3510);
DISPLAY 1.617021 (7010 3510);
PAINT MONO (7010 3510);
DISPLAY INVISIBLE (7010 3510);
FORCEPROP 1 LAST PATH I30
J 2
(7000 3450);
DISPLAY 0.978723 (7000 3450);
PAINT WHITE (7000 3450);
DISPLAY INVISIBLE (7000 3450);
FORCEPROP 2 LAST ROOM P1V538_BMC_STBY_VR
J 2
(7000 3425);
DISPLAY 1.212766 (7000 3425);
PAINT GREEN (7000 3425);
DISPLAY INVISIBLE (7000 3425);
FORCEPROP 2 LAST BOM_COST P1V538_BMC_STBY_VR
J 0
(6985 3410);
DISPLAY 1.617021 (6985 3410);
PAINT WHITE (6985 3410);
DISPLAY INVISIBLE (6985 3410);
FORCEADD OFFPAGE..1
(6375 3575);
FORCEPROP 2 LAST $XR2 189 
J 0
(5883 3575);
DISPLAY 0.638298 (5883 3575);
PAINT MONO (5883 3575);
FORCEPROP 2 LAST $XR0 240 
J 0
(6123 3575);
DISPLAY 0.638298 (6123 3575);
PAINT MONO (6123 3575);
FORCEPROP 2 LAST $XR5 237 
J 0
(5523 3575);
DISPLAY 0.638298 (5523 3575);
PAINT MONO (5523 3575);
FORCEPROP 2 LAST $XR4 196 
J 0
(5643 3575);
DISPLAY 0.638298 (5643 3575);
PAINT MONO (5643 3575);
FORCEPROP 2 LAST $XR3 191 
J 0
(5763 3575);
DISPLAY 0.638298 (5763 3575);
PAINT MONO (5763 3575);
FORCEPROP 2 LAST $XR1 101 
J 0
(6003 3575);
DISPLAY 0.638298 (6003 3575);
PAINT MONO (6003 3575);
FORCEPROP 2 LAST CDS_LIB mstr_standard
J 0
(6375 3575);
DISPLAY 1.340426 (6375 3575);
PAINT ORANGE (6375 3575);
DISPLAY INVISIBLE (6375 3575);
FORCEPROP 2 LAST PATH I33
J 0
(6449 3649);
DISPLAY 1.021277 (6449 3649);
PAINT ORANGE (6449 3649);
DISPLAY INVISIBLE (6449 3649);
FORCEPROP 2 LAST BOM_COST P1V538_BMC_STBY_VR
J 0
(6100 3625);
PAINT WHITE (6100 3625);
DISPLAY INVISIBLE (6100 3625);
FORCEPROP 2 LAST ROOM P1V538_BMC_STBY_VR
J 0
(5900 3650);
DISPLAY 1.340426 (5900 3650);
PAINT GREEN (5900 3650);
DISPLAY INVISIBLE (5900 3650);
FORCEPROP 1 LAST OFFPAGE TRUE
J 0
(6700 3450);
PAINT GREEN (6700 3450);
DISPLAY INVISIBLE (6700 3450);
FORCEPROP 1 LAST COMMENT_BODY TRUE
J 0
(6500 3475);
DISPLAY 1.170213 (6500 3475);
PAINT PEACH (6500 3475);
DISPLAY INVISIBLE (6500 3475);
FORCEADD P3V3_STBY..1
(9625 5000);
FORCEPROP 3 LASTPIN (9625 4950) SIG_NAME P3V3_STBY\g
J 0
(9635 4960);
DISPLAY 0.659574 (9635 4960);
PAINT MONO (9635 4960);
DISPLAY INVISIBLE (9635 4960);
FORCEPROP 2 LAST CDS_LIB mstr_symbols
J 0
(9625 5000);
PAINT ORANGE (9625 5000);
DISPLAY INVISIBLE (9625 5000);
FORCEPROP 1 LAST PATH I35
J 0
(9670 5002);
DISPLAY 0.340426 (9670 5002);
PAINT GREEN (9670 5002);
DISPLAY INVISIBLE (9670 5002);
FORCEPROP 1 LAST SIZE 1B
J 0
(9670 5022);
DISPLAY 0.340426 (9670 5022);
PAINT GREEN (9670 5022);
DISPLAY INVISIBLE (9670 5022);
FORCEPROP 1 LAST VOLTAGE 3.3V
J 0
(9580 4957);
DISPLAY 0.340426 (9580 4957);
PAINT SKYBLUE (9580 4957);
DISPLAY INVISIBLE (9580 4957);
FORCEPROP 1 LAST BODY_TYPE PLUMBING
J 0
(9580 4957);
DISPLAY 0.340426 (9580 4957);
PAINT GREEN (9580 4957);
DISPLAY INVISIBLE (9580 4957);
FORCEPROP 1 LAST HDL_POWER P3V3_STBY
J 0
(9325 4875);
DISPLAY 0.872340 (9325 4875);
PAINT ORANGE (9325 4875);
DISPLAY INVISIBLE (9325 4875);
FORCEADD GND..1
(7050 2875);
FORCEPROP 3 LASTPIN (7050 2925) SIG_NAME GND\g
J 0
(7060 2935);
DISPLAY 0.659574 (7060 2935);
PAINT MONO (7060 2935);
DISPLAY INVISIBLE (7060 2935);
FORCEPROP 2 LAST P1V5_STBY_IBMC 
J 0
(7075 3000);
PAINT GREEN (7075 3000);
FORCEPROP 2 LAST P1V5_STBY_IBMC_VR 
J 0
(7075 2950);
PAINT GREEN (7075 2950);
FORCEPROP 2 LAST CDS_LIB mstr_symbols
J 0
(7050 2875);
PAINT ORANGE (7050 2875);
DISPLAY INVISIBLE (7050 2875);
FORCEPROP 1 LAST PATH I38
J 0
(7125 2875);
DISPLAY 0.872340 (7125 2875);
PAINT AQUA (7125 2875);
DISPLAY INVISIBLE (7125 2875);
FORCEPROP 2 LAST BOM_COST P1V538_BMC_STBY_VR
J 0
(7075 3050);
PAINT WHITE (7075 3050);
DISPLAY INVISIBLE (7075 3050);
FORCEPROP 1 LAST VOLTAGE 0.0V
J 0
(7005 2832);
DISPLAY 0.340426 (7005 2832);
PAINT SKYBLUE (7005 2832);
DISPLAY INVISIBLE (7005 2832);
FORCEPROP 1 LAST SIZE 1B
J 0
(7125 2825);
DISPLAY 0.872340 (7125 2825);
PAINT ORANGE (7125 2825);
DISPLAY INVISIBLE (7125 2825);
FORCEPROP 2 LAST ROOM P1V538_BMC_STBY_VR
J 0
(6700 2950);
DISPLAY 0.872340 (6700 2950);
PAINT GREEN (6700 2950);
DISPLAY INVISIBLE (6700 2950);
FORCEPROP 1 LAST BODY_TYPE PLUMBING
J 0
(7005 2832);
DISPLAY 0.340426 (7005 2832);
PAINT GREEN (7005 2832);
DISPLAY INVISIBLE (7005 2832);
FORCEPROP 1 LAST HDL_POWER GND
J 0
(7050 3025);
DISPLAY 0.872340 (7050 3025);
PAINT GREEN (7050 3025);
DISPLAY INVISIBLE (7050 3025);
FORCEADD GND..1
(6525 3850);
FORCEPROP 3 LASTPIN (6525 3900) SIG_NAME GND\g
J 0
(6535 3910);
DISPLAY 0.659574 (6535 3910);
PAINT MONO (6535 3910);
DISPLAY INVISIBLE (6535 3910);
FORCEPROP 2 LAST CDS_LIB mstr_symbols
J 0
(6525 3850);
PAINT ORANGE (6525 3850);
DISPLAY INVISIBLE (6525 3850);
FORCEPROP 1 LAST PATH I39
J 0
(6600 3850);
DISPLAY 0.872340 (6600 3850);
PAINT AQUA (6600 3850);
DISPLAY INVISIBLE (6600 3850);
FORCEPROP 1 LAST SIZE 1B
J 0
(6600 3800);
DISPLAY 0.872340 (6600 3800);
PAINT AQUA (6600 3800);
DISPLAY INVISIBLE (6600 3800);
FORCEPROP 1 LAST VOLTAGE 0.0V
J 0
(6480 3807);
DISPLAY 0.340426 (6480 3807);
PAINT SKYBLUE (6480 3807);
DISPLAY INVISIBLE (6480 3807);
FORCEPROP 1 LAST BODY_TYPE PLUMBING
J 0
(6480 3807);
DISPLAY 0.340426 (6480 3807);
PAINT GREEN (6480 3807);
DISPLAY INVISIBLE (6480 3807);
FORCEPROP 1 LAST HDL_POWER GND
J 0
(6525 4000);
DISPLAY 0.872340 (6525 4000);
PAINT GREEN (6525 4000);
DISPLAY INVISIBLE (6525 4000);
FORCEADD CAP..1
(10375 4150);
FORCEPROP 1 LASTPIN (10375 4250) $PN 1
J 0
(10385 4230);
DISPLAY 0.617021 (10385 4230);
PAINT WHITE (10385 4230);
FORCEPROP 1 LASTPIN (10375 4050) $PN 2
J 0
(10385 4030);
DISPLAY 0.617021 (10385 4030);
PAINT WHITE (10385 4030);
FORCEPROP 1 LAST VALUE 1000PF
J 0
(10425 4200);
DISPLAY 0.617021 (10425 4200);
PAINT SKYBLUE (10425 4200);
FORCEPROP 1 LAST PACK_TYPE 0402LF
J 0
(10425 3950);
DISPLAY 0.617021 (10425 3950);
PAINT SKYBLUE (10425 3950);
FORCEPROP 1 LAST LOCATION C9F10
J 0
(10250 4225);
DISPLAY 0.617021 (10250 4225);
PAINT AQUA (10250 4225);
FORCEPROP 1 LAST TOLERANCE 10%
J 0
(10425 4100);
DISPLAY 0.617021 (10425 4100);
PAINT SKYBLUE (10425 4100);
FORCEPROP 1 LAST MATERIAL X7R
J 0
(10425 4050);
DISPLAY 0.617021 (10425 4050);
PAINT SKYBLUE (10425 4050);
FORCEPROP 1 LAST PART_NUMBER A36096-046
J 0
(10425 4000);
DISPLAY 0.617021 (10425 4000);
PAINT BLUE (10425 4000);
FORCEPROP 2 LAST CDS_SEC 1
J 0
(10435 4365);
DISPLAY 1.617021 (10435 4365);
PAINT MONO (10435 4365);
DISPLAY INVISIBLE (10435 4365);
FORCEPROP 2 LAST CDS_LIB mstr_discrete
J 0
(10375 4150);
DISPLAY 1.617021 (10375 4150);
PAINT MONO (10375 4150);
DISPLAY INVISIBLE (10375 4150);
FORCEPROP 2 LAST CDS_LOCATION C9F10
J 0
(10250 4225);
DISPLAY 0.617021 (10250 4225);
PAINT AQUA (10250 4225);
DISPLAY INVISIBLE (10250 4225);
FORCEPROP 2 LAST $SEC 1
J 0
(10435 4365);
DISPLAY 1.617021 (10435 4365);
PAINT MONO (10435 4365);
DISPLAY INVISIBLE (10435 4365);
FORCEPROP 1 LAST PATH I4
J 0
(10425 4300);
DISPLAY 0.978723 (10425 4300);
PAINT WHITE (10425 4300);
DISPLAY INVISIBLE (10425 4300);
FORCEPROP 1 LAST VOLTAGE 50V
J 0
(10425 4150);
DISPLAY 1.617021 (10425 4150);
PAINT SKYBLUE (10425 4150);
DISPLAY INVISIBLE (10425 4150);
FORCEPROP 2 LAST BOM_COST P1V538_BMC_STBY_VR
J 0
(10435 4290);
DISPLAY 1.617021 (10435 4290);
PAINT WHITE (10435 4290);
DISPLAY INVISIBLE (10435 4290);
FORCEPROP 2 LAST ROOM P1V538_BMC_STBY_VR
J 0
(10435 4290);
DISPLAY 1.617021 (10435 4290);
PAINT GREEN (10435 4290);
DISPLAY INVISIBLE (10435 4290);
FORCEADD OFFPAGE..2
(11550 4275);
FORCEPROP 2 LAST $XR0 238 
J 0
(11739 4275);
DISPLAY 0.638298 (11739 4275);
PAINT MONO (11739 4275);
FORCEPROP 2 LAST CDS_LIB mstr_standard
J 0
(11550 4275);
PAINT ORANGE (11550 4275);
DISPLAY INVISIBLE (11550 4275);
FORCEPROP 2 LAST PATH I42
J 0
(11725 4350);
DISPLAY 1.021277 (11725 4350);
PAINT ORANGE (11725 4350);
DISPLAY INVISIBLE (11725 4350);
FORCEPROP 1 LAST OFFPAGE TRUE
J 0
(11875 4150);
DISPLAY 0.872340 (11875 4150);
PAINT GREEN (11875 4150);
DISPLAY INVISIBLE (11875 4150);
FORCEPROP 1 LAST COMMENT_BODY TRUE
J 0
(11505 4180);
DISPLAY 0.872340 (11505 4180);
PAINT GREEN (11505 4180);
DISPLAY INVISIBLE (11505 4180);
FORCEADD GND..1
(10375 3975);
FORCEPROP 3 LASTPIN (10375 4025) SIG_NAME GND\g
J 0
(10385 4035);
DISPLAY 0.659574 (10385 4035);
PAINT MONO (10385 4035);
DISPLAY INVISIBLE (10385 4035);
FORCEPROP 2 LAST CDS_LIB mstr_symbols
J 0
(10375 3975);
DISPLAY 1.617021 (10375 3975);
PAINT MONO (10375 3975);
DISPLAY INVISIBLE (10375 3975);
FORCEPROP 1 LAST PATH I5
J 0
(10450 3975);
DISPLAY 0.872340 (10450 3975);
PAINT AQUA (10450 3975);
DISPLAY INVISIBLE (10450 3975);
FORCEPROP 2 LAST BOM_COST P1V538_BMC_STBY_VR
J 0
(10060 4065);
DISPLAY 1.617021 (10060 4065);
PAINT WHITE (10060 4065);
DISPLAY INVISIBLE (10060 4065);
FORCEPROP 1 LAST SIZE 1B
J 0
(10450 3925);
DISPLAY 1.063830 (10450 3925);
PAINT GREEN (10450 3925);
DISPLAY INVISIBLE (10450 3925);
FORCEPROP 1 LAST VOLTAGE 0.0V
J 0
(10330 3932);
DISPLAY 0.340426 (10330 3932);
PAINT SKYBLUE (10330 3932);
DISPLAY INVISIBLE (10330 3932);
FORCEPROP 2 LAST ROOM P1V538_BMC_STBY_VR
J 0
(9725 4050);
DISPLAY 1.212766 (9725 4050);
PAINT GREEN (9725 4050);
DISPLAY INVISIBLE (9725 4050);
FORCEPROP 1 LAST BODY_TYPE PLUMBING
J 0
(10330 3932);
DISPLAY 0.340426 (10330 3932);
PAINT GREEN (10330 3932);
DISPLAY INVISIBLE (10330 3932);
FORCEPROP 1 LAST HDL_POWER GND
J 0
(10375 4125);
DISPLAY 1.063830 (10375 4125);
PAINT GREEN (10375 4125);
DISPLAY INVISIBLE (10375 4125);
FORCEADD RES..2
(9625 4525);
FORCEPROP 1 LAST PART_NUMBER G21796-016
J 0
(9665 4400);
DISPLAY 0.617021 (9665 4400);
PAINT BLUE (9665 4400);
FORCEPROP 2 LAST P1V5_STBY_IBMC 
J 0
(9575 4725);
PAINT GREEN (9575 4725);
FORCEPROP 2 LAST P1V5_STBY_IBMC_VR 
J 0
(9575 4675);
PAINT GREEN (9575 4675);
FORCEPROP 1 LASTPIN (9625 4625) $PN 1
J 0
(9630 4587);
DISPLAY 0.617021 (9630 4587);
PAINT WHITE (9630 4587);
FORCEPROP 1 LASTPIN (9625 4425) $PN 2
J 0
(9630 4435);
DISPLAY 0.617021 (9630 4435);
PAINT WHITE (9630 4435);
FORCEPROP 1 LAST LOCATION R9F12
J 0
(9670 4650);
DISPLAY 0.617021 (9670 4650);
PAINT AQUA (9670 4650);
FORCEPROP 1 LAST WATTAGE 1/16W
J 0
(9665 4500);
DISPLAY 0.617021 (9665 4500);
PAINT SKYBLUE (9665 4500);
FORCEPROP 1 LAST VALUE 10.0K
J 0
(9670 4600);
DISPLAY 0.617021 (9670 4600);
PAINT SKYBLUE (9670 4600);
FORCEPROP 1 LAST MATERIAL CHIP
J 0
(9665 4450);
DISPLAY 0.617021 (9665 4450);
PAINT SKYBLUE (9665 4450);
FORCEPROP 1 LAST PACK_TYPE 0402
J 0
(9665 4350);
DISPLAY 0.617021 (9665 4350);
PAINT SKYBLUE (9665 4350);
FORCEPROP 1 LAST TOLERANCE 1%
J 0
(9670 4550);
DISPLAY 0.617021 (9670 4550);
PAINT SKYBLUE (9670 4550);
FORCEPROP 2 LAST CDS_LOCATION R9F12
J 0
(9670 4650);
DISPLAY 0.617021 (9670 4650);
PAINT AQUA (9670 4650);
DISPLAY INVISIBLE (9670 4650);
FORCEPROP 2 LAST CDS_LIB mstr_discrete
J 0
(9625 4525);
PAINT ORANGE (9625 4525);
DISPLAY INVISIBLE (9625 4525);
FORCEPROP 2 LAST SEC_TYPE 0402
J 0
(9575 4775);
DISPLAY 1.659574 (9575 4775);
PAINT ORANGE (9575 4775);
DISPLAY INVISIBLE (9575 4775);
FORCEPROP 2 LAST SEC 1
J 0
(9575 4775);
DISPLAY 1.106383 (9575 4775);
PAINT MONO (9575 4775);
DISPLAY INVISIBLE (9575 4775);
FORCEPROP 1 LAST PATH I6
J 0
(9675 4700);
DISPLAY 0.978723 (9675 4700);
PAINT WHITE (9675 4700);
DISPLAY INVISIBLE (9675 4700);
FORCEPROP 2 LAST BOM_COST P1V538_BMC_STBY_VR
J 0
(9575 4775);
PAINT WHITE (9575 4775);
DISPLAY INVISIBLE (9575 4775);
FORCEPROP 2 LAST ROOM P1V538_BMC_STBY_VR
J 0
(9575 4625);
PAINT GREEN (9575 4625);
DISPLAY INVISIBLE (9575 4625);
FORCEADD GND..1
(9450 3350);
FORCEPROP 3 LASTPIN (9450 3400) SIG_NAME GND\g
J 0
(9460 3410);
DISPLAY 0.659574 (9460 3410);
PAINT MONO (9460 3410);
DISPLAY INVISIBLE (9460 3410);
FORCEPROP 2 LAST P1V5_STBY_IBMC_VR 
J 0
(9475 3425);
PAINT GREEN (9475 3425);
FORCEPROP 2 LAST P1V5_STBY_IBMC 
J 0
(9475 3475);
PAINT GREEN (9475 3475);
FORCEPROP 2 LAST CDS_LIB mstr_symbols
J 0
(9450 3350);
PAINT ORANGE (9450 3350);
DISPLAY INVISIBLE (9450 3350);
FORCEPROP 1 LAST PATH I62
J 0
(9525 3350);
DISPLAY 0.872340 (9525 3350);
PAINT AQUA (9525 3350);
DISPLAY INVISIBLE (9525 3350);
FORCEPROP 1 LAST SIZE 1B
J 0
(9525 3300);
DISPLAY 0.872340 (9525 3300);
PAINT ORANGE (9525 3300);
DISPLAY INVISIBLE (9525 3300);
FORCEPROP 2 LAST BOM_COST P1V26_BMC_STBY_VR
J 0
(9475 3525);
PAINT WHITE (9475 3525);
DISPLAY INVISIBLE (9475 3525);
FORCEPROP 1 LAST VOLTAGE 0.0V
J 0
(9405 3307);
DISPLAY 0.340426 (9405 3307);
PAINT SKYBLUE (9405 3307);
DISPLAY INVISIBLE (9405 3307);
FORCEPROP 2 LAST ROOM P1V26_BMC_STBY_VR
J 0
(9100 3425);
DISPLAY 0.872340 (9100 3425);
PAINT GREEN (9100 3425);
DISPLAY INVISIBLE (9100 3425);
FORCEPROP 1 LAST BODY_TYPE PLUMBING
J 0
(9405 3307);
DISPLAY 0.340426 (9405 3307);
PAINT GREEN (9405 3307);
DISPLAY INVISIBLE (9405 3307);
FORCEPROP 1 LAST HDL_POWER GND
J 0
(9450 3500);
DISPLAY 0.872340 (9450 3500);
PAINT GREEN (9450 3500);
DISPLAY INVISIBLE (9450 3500);
FORCEADD P3V3_STBY..1
(6525 4625);
FORCEPROP 3 LASTPIN (6525 4575) SIG_NAME P3V3_STBY\g
J 0
(6535 4585);
DISPLAY 0.659574 (6535 4585);
PAINT MONO (6535 4585);
DISPLAY INVISIBLE (6535 4585);
FORCEPROP 2 LAST CDS_LIB mstr_symbols
J 0
(6525 4625);
PAINT ORANGE (6525 4625);
DISPLAY INVISIBLE (6525 4625);
FORCEPROP 1 LAST PATH I67
J 0
(6570 4627);
DISPLAY 0.340426 (6570 4627);
PAINT GREEN (6570 4627);
DISPLAY INVISIBLE (6570 4627);
FORCEPROP 1 LAST SIZE 1B
J 0
(6570 4647);
DISPLAY 0.340426 (6570 4647);
PAINT GREEN (6570 4647);
DISPLAY INVISIBLE (6570 4647);
FORCEPROP 1 LAST VOLTAGE 3.3V
J 0
(6480 4582);
DISPLAY 0.340426 (6480 4582);
PAINT SKYBLUE (6480 4582);
DISPLAY INVISIBLE (6480 4582);
FORCEPROP 1 LAST BODY_TYPE PLUMBING
J 0
(6480 4582);
DISPLAY 0.340426 (6480 4582);
PAINT GREEN (6480 4582);
DISPLAY INVISIBLE (6480 4582);
FORCEPROP 1 LAST HDL_POWER P3V3_STBY
J 0
(6225 4500);
DISPLAY 0.872340 (6225 4500);
PAINT ORANGE (6225 4500);
DISPLAY INVISIBLE (6225 4500);
FORCEADD GND..1
(7475 3850);
FORCEPROP 3 LASTPIN (7475 3900) SIG_NAME GND\g
J 0
(7485 3910);
DISPLAY 0.659574 (7485 3910);
PAINT MONO (7485 3910);
DISPLAY INVISIBLE (7485 3910);
FORCEPROP 2 LAST P1V5_STBY_IBMC_VR 
J 0
(7500 3925);
PAINT GREEN (7500 3925);
FORCEPROP 2 LAST P1V5_STBY_IBMC 
J 0
(7500 3975);
PAINT GREEN (7500 3975);
FORCEPROP 2 LAST CDS_LIB mstr_symbols
J 0
(7475 3850);
PAINT ORANGE (7475 3850);
DISPLAY INVISIBLE (7475 3850);
FORCEPROP 1 LAST PATH I69
J 0
(7550 3850);
DISPLAY 0.872340 (7550 3850);
PAINT AQUA (7550 3850);
DISPLAY INVISIBLE (7550 3850);
FORCEPROP 2 LAST BOM_COST P1V26_BMC_STBY_VR
J 0
(7500 4025);
PAINT WHITE (7500 4025);
DISPLAY INVISIBLE (7500 4025);
FORCEPROP 1 LAST SIZE 1B
J 0
(7550 3800);
DISPLAY 0.872340 (7550 3800);
PAINT ORANGE (7550 3800);
DISPLAY INVISIBLE (7550 3800);
FORCEPROP 1 LAST VOLTAGE 0.0V
J 0
(7430 3807);
DISPLAY 0.340426 (7430 3807);
PAINT SKYBLUE (7430 3807);
DISPLAY INVISIBLE (7430 3807);
FORCEPROP 2 LAST ROOM P1V26_BMC_STBY_VR
J 0
(7125 3925);
DISPLAY 0.872340 (7125 3925);
PAINT GREEN (7125 3925);
DISPLAY INVISIBLE (7125 3925);
FORCEPROP 1 LAST BODY_TYPE PLUMBING
J 0
(7430 3807);
DISPLAY 0.340426 (7430 3807);
PAINT GREEN (7430 3807);
DISPLAY INVISIBLE (7430 3807);
FORCEPROP 1 LAST HDL_POWER GND
J 0
(7475 4000);
DISPLAY 0.872340 (7475 4000);
PAINT GREEN (7475 4000);
DISPLAY INVISIBLE (7475 4000);
FORCEADD CAP..1
(11300 3550);
FORCEPROP 1 LAST PACK_TYPE 0805LF
J 0
(11350 3350);
DISPLAY 0.617021 (11350 3350);
PAINT SKYBLUE (11350 3350);
FORCEPROP 1 LASTPIN (11300 3650) $PN 1
J 0
(11310 3630);
DISPLAY 0.617021 (11310 3630);
PAINT WHITE (11310 3630);
FORCEPROP 1 LAST VOLTAGE 4V
J 0
(11350 3550);
DISPLAY 0.617021 (11350 3550);
PAINT SKYBLUE (11350 3550);
FORCEPROP 1 LAST MATERIAL X6S
J 0
(11350 3450);
DISPLAY 0.617021 (11350 3450);
PAINT SKYBLUE (11350 3450);
FORCEPROP 1 LAST LOCATION C9F13
J 0
(11350 3650);
DISPLAY 0.617021 (11350 3650);
PAINT AQUA (11350 3650);
FORCEPROP 1 LAST VALUE 22UF
J 0
(11350 3600);
DISPLAY 0.617021 (11350 3600);
PAINT SKYBLUE (11350 3600);
FORCEPROP 1 LASTPIN (11300 3450) $PN 2
J 0
(11310 3430);
DISPLAY 0.617021 (11310 3430);
PAINT WHITE (11310 3430);
FORCEPROP 1 LAST PART_NUMBER C95333-002
J 0
(11350 3400);
DISPLAY 0.617021 (11350 3400);
PAINT BLUE (11350 3400);
FORCEPROP 1 LAST TOLERANCE 20%
J 0
(11350 3500);
DISPLAY 0.617021 (11350 3500);
PAINT SKYBLUE (11350 3500);
FORCEPROP 2 LAST CDS_LOCATION C9F13
J 0
(11350 3650);
DISPLAY 0.617021 (11350 3650);
PAINT AQUA (11350 3650);
DISPLAY INVISIBLE (11350 3650);
FORCEPROP 2 LAST CDS_LIB mstr_discrete
J 0
(11300 3550);
PAINT ORANGE (11300 3550);
DISPLAY INVISIBLE (11300 3550);
FORCEPROP 2 LAST SEC 1
J 0
(11350 3750);
DISPLAY 1.106383 (11350 3750);
PAINT MONO (11350 3750);
DISPLAY INVISIBLE (11350 3750);
FORCEPROP 2 LAST SEC_TYPE 0805LF
J 0
(11350 3750);
DISPLAY 1.659574 (11350 3750);
PAINT ORANGE (11350 3750);
DISPLAY INVISIBLE (11350 3750);
FORCEPROP 1 LAST PATH I7
J 0
(11350 3700);
DISPLAY 0.978723 (11350 3700);
PAINT WHITE (11350 3700);
DISPLAY INVISIBLE (11350 3700);
FORCEPROP 2 LAST ROOM P1V538_BMC_STBY_VR
J 0
(11350 3750);
PAINT GREEN (11350 3750);
DISPLAY INVISIBLE (11350 3750);
FORCEPROP 2 LAST BOM_COST P1V538_BMC_STBY_VR
J 0
(11350 3700);
PAINT WHITE (11350 3700);
DISPLAY INVISIBLE (11350 3700);
FORCEADD RT9059..1
(8850 3775);
FORCEPROP 1 LAST PART_NUMBER H65765-001
J 0
(8400 3375);
DISPLAY 0.617021 (8400 3375);
PAINT BLUE (8400 3375);
FORCEPROP 2 LASTPIN (9350 3975) $PN 5
J 0
(9360 3985);
DISPLAY 0.617021 (9360 3985);
PAINT ORANGE (9360 3985);
FORCEPROP 2 LASTPIN (9350 3775) $PN 2
J 0
(9360 3785);
DISPLAY 0.617021 (9360 3785);
PAINT ORANGE (9360 3785);
FORCEPROP 2 LASTPIN (9350 3825) $PN 3
J 0
(9360 3835);
DISPLAY 0.617021 (9360 3835);
PAINT ORANGE (9360 3835);
FORCEPROP 2 LASTPIN (9350 3725) $PN 1
J 0
(9360 3735);
DISPLAY 0.617021 (9360 3735);
PAINT ORANGE (9360 3735);
FORCEPROP 2 LASTPIN (9350 3575) $PN 4
J 0
(9360 3585);
DISPLAY 0.617021 (9360 3585);
PAINT ORANGE (9360 3585);
FORCEPROP 2 LASTPIN (9350 3475) $PN 11
J 0
(9360 3485);
DISPLAY 0.617021 (9360 3485);
PAINT ORANGE (9360 3485);
FORCEPROP 2 LASTPIN (8350 3825) $PN 9
J 2
(8340 3835);
DISPLAY 0.617021 (8340 3835);
PAINT ORANGE (8340 3835);
FORCEPROP 2 LASTPIN (8350 3775) $PN 8
J 2
(8340 3785);
DISPLAY 0.617021 (8340 3785);
PAINT ORANGE (8340 3785);
FORCEPROP 2 LASTPIN (8350 3725) $PN 7
J 2
(8340 3735);
DISPLAY 0.617021 (8340 3735);
PAINT ORANGE (8340 3735);
FORCEPROP 2 LASTPIN (8350 3975) $PN 10
J 2
(8340 3985);
DISPLAY 0.617021 (8340 3985);
PAINT ORANGE (8340 3985);
FORCEPROP 2 LASTPIN (8350 3575) $PN 6
J 2
(8340 3585);
DISPLAY 0.617021 (8340 3585);
PAINT ORANGE (8340 3585);
FORCEPROP 1 LAST LOCATION EU9F2
J 0
(8400 4225);
DISPLAY 0.617021 (8400 4225);
PAINT AQUA (8400 4225);
FORCEPROP 1 LAST MATERIAL IC
J 0
(8400 4175);
DISPLAY 0.617021 (8400 4175);
PAINT SKYBLUE (8400 4175);
FORCEPROP 2 LAST CDS_LIB mstr_vreg
J 0
(8850 3775);
PAINT ORANGE (8850 3775);
DISPLAY INVISIBLE (8850 3775);
FORCEPROP 2 LAST CDS_LOCATION EU9F2
J 0
(8400 4225);
DISPLAY 0.617021 (8400 4225);
PAINT AQUA (8400 4225);
DISPLAY INVISIBLE (8400 4225);
FORCEPROP 2 LAST SEC_TYPE DFN
J 0
(8400 4275);
DISPLAY 1.021277 (8400 4275);
PAINT ORANGE (8400 4275);
DISPLAY INVISIBLE (8400 4275);
FORCEPROP 2 LAST SEC 1
J 0
(8400 4275);
DISPLAY 0.680851 (8400 4275);
PAINT MONO (8400 4275);
DISPLAY INVISIBLE (8400 4275);
FORCEPROP 1 LAST PATH I70
J 0
(8900 4175);
PAINT GREEN (8900 4175);
DISPLAY INVISIBLE (8900 4175);
FORCEPROP 1 LAST PACK_TYPE DFN
J 0
(8400 4275);
PAINT SKYBLUE (8400 4275);
DISPLAY INVISIBLE (8400 4275);
FORCEADD CAP_A..1
(7475 4125);
FORCEPROP 1 LAST LOCATION C9F5
J 0
(7525 4225);
DISPLAY 0.617021 (7525 4225);
PAINT AQUA (7525 4225);
FORCEPROP 1 LASTPIN (7475 4225) $PN 1
J 0
(7485 4205);
DISPLAY 0.617021 (7485 4205);
PAINT ORANGE (7485 4205);
FORCEPROP 1 LASTPIN (7475 4025) $PN 2
J 0
(7485 4005);
DISPLAY 0.617021 (7485 4005);
PAINT ORANGE (7485 4005);
FORCEPROP 1 LAST VALUE 0.1UF
J 0
(7525 4175);
DISPLAY 0.617021 (7525 4175);
PAINT SKYBLUE (7525 4175);
FORCEPROP 1 LAST VOLTAGE 16V
J 0
(7525 4125);
DISPLAY 0.617021 (7525 4125);
PAINT SKYBLUE (7525 4125);
FORCEPROP 1 LAST PART_NUMBER A36096-030
J 0
(7525 3975);
DISPLAY 0.617021 (7525 3975);
PAINT BLUE (7525 3975);
FORCEPROP 1 LAST TOLERANCE 10%
J 0
(7525 4075);
DISPLAY 0.617021 (7525 4075);
PAINT SKYBLUE (7525 4075);
FORCEPROP 1 LAST PACK_TYPE 0402V
J 0
(7525 3925);
DISPLAY 0.617021 (7525 3925);
PAINT SKYBLUE (7525 3925);
FORCEPROP 1 LAST MATERIAL X7R
J 0
(7525 4025);
DISPLAY 0.617021 (7525 4025);
PAINT SKYBLUE (7525 4025);
FORCEPROP 2 LAST CDS_LOCATION C9F5
J 0
(7525 4225);
DISPLAY 0.617021 (7525 4225);
PAINT AQUA (7525 4225);
DISPLAY INVISIBLE (7525 4225);
FORCEPROP 2 LAST CDS_LIB dev_discrete
J 0
(7475 4125);
PAINT ORANGE (7475 4125);
DISPLAY INVISIBLE (7475 4125);
FORCEPROP 2 LAST CDS_SEC 1
J 0
(7525 4275);
PAINT ORANGE (7525 4275);
DISPLAY INVISIBLE (7525 4275);
FORCEPROP 2 LAST SEC_TYPE 0402V
J 0
(7525 4325);
DISPLAY 1.021277 (7525 4325);
PAINT ORANGE (7525 4325);
DISPLAY INVISIBLE (7525 4325);
FORCEPROP 2 LAST SEC 1
J 0
(7525 4325);
PAINT MONO (7525 4325);
DISPLAY INVISIBLE (7525 4325);
FORCEPROP 1 LAST PATH I71
J 0
(7525 4275);
DISPLAY 0.978723 (7525 4275);
PAINT WHITE (7525 4275);
DISPLAY INVISIBLE (7525 4275);
FORCEADD RES..1
(10700 4275);
FORCEPROP 1 LAST TOLERANCE 1.0%
J 0
(10700 4175);
DISPLAY 0.617021 (10700 4175);
PAINT SKYBLUE (10700 4175);
FORCEPROP 1 LAST MATERIAL CHIP
J 0
(10700 4125);
DISPLAY 0.617021 (10700 4125);
PAINT SKYBLUE (10700 4125);
FORCEPROP 1 LASTPIN (10800 4275) $PN 2
J 0
(10762 4287);
DISPLAY 0.617021 (10762 4287);
PAINT ORANGE (10762 4287);
FORCEPROP 1 LASTPIN (10600 4275) $PN 1
J 0
(10612 4287);
DISPLAY 0.617021 (10612 4287);
PAINT ORANGE (10612 4287);
FORCEPROP 1 LAST PACK_TYPE 0402
J 0
(10950 4125);
DISPLAY 0.617021 (10950 4125);
PAINT SKYBLUE (10950 4125);
FORCEPROP 1 LAST PART_NUMBER G21796-250
J 0
(10650 4375);
DISPLAY 0.617021 (10650 4375);
PAINT BLUE (10650 4375);
FORCEPROP 1 LAST LOCATION R1T9
J 0
(10650 4325);
DISPLAY 0.617021 (10650 4325);
PAINT AQUA (10650 4325);
FORCEPROP 1 LAST WATTAGE 1/16W
J 2
(10675 4125);
DISPLAY 0.617021 (10675 4125);
PAINT SKYBLUE (10675 4125);
FORCEPROP 1 LAST VALUE 22.1
J 2
(10675 4175);
DISPLAY 0.617021 (10675 4175);
PAINT SKYBLUE (10675 4175);
FORCEPROP 2 LAST CDS_LIB mstr_discrete
J 0
(10700 4275);
PAINT MONO (10700 4275);
DISPLAY INVISIBLE (10700 4275);
FORCEPROP 2 LAST CDS_LOCATION R1T9
J 0
(10650 4325);
DISPLAY 0.617021 (10650 4325);
PAINT AQUA (10650 4325);
DISPLAY INVISIBLE (10650 4325);
FORCEPROP 2 LAST SEC_TYPE 0402
J 0
(10650 4475);
DISPLAY 1.021277 (10650 4475);
PAINT ORANGE (10650 4475);
DISPLAY INVISIBLE (10650 4475);
FORCEPROP 2 LAST SEC 1
J 0
(10650 4475);
DISPLAY 0.680851 (10650 4475);
PAINT MONO (10650 4475);
DISPLAY INVISIBLE (10650 4475);
FORCEPROP 1 LAST PATH I72
J 0
(10650 4425);
DISPLAY 0.978723 (10650 4425);
PAINT WHITE (10650 4425);
DISPLAY INVISIBLE (10650 4425);
FORCEPROP 0 LAST ROOM P1V538_BMC_STBY_VR
J 0
(10650 4475);
DISPLAY 1.021277 (10650 4475);
PAINT ORANGE (10650 4475);
DISPLAY INVISIBLE (10650 4475);
FORCEADD RT9059..1
(8425 1700);
FORCEPROP 1 LAST PART_NUMBER H65765-001
J 0
(7975 1300);
DISPLAY 0.617021 (7975 1300);
PAINT BLUE (7975 1300);
FORCEPROP 1 LAST LOCATION EU25F2
J 0
(7975 2150);
DISPLAY 0.617021 (7975 2150);
PAINT AQUA (7975 2150);
FORCEPROP 1 LAST MATERIAL IC
J 0
(7975 2100);
DISPLAY 0.617021 (7975 2100);
PAINT SKYBLUE (7975 2100);
FORCEPROP 1 LAST PACK_TYPE DFN
J 0
(7975 2200);
PAINT SKYBLUE (7975 2200);
DISPLAY INVISIBLE (7975 2200);
FORCEPROP 1 LAST PATH I73
J 0
(8475 2100);
PAINT GREEN (8475 2100);
DISPLAY INVISIBLE (8475 2100);
FORCEPROP 2 LAST CDS_LIB mstr_vreg
J 0
(8425 1700);
PAINT MONO (8425 1700);
DISPLAY INVISIBLE (8425 1700);
FORCEADD GND..1
(7050 1775);
FORCEPROP 3 LASTPIN (7050 1825) SIG_NAME GND\g
J 0
(7060 1835);
DISPLAY 0.659574 (7060 1835);
PAINT MONO (7060 1835);
DISPLAY INVISIBLE (7060 1835);
FORCEPROP 2 LAST P1V5_STBY_IBMC 
J 0
(7075 1900);
PAINT GREEN (7075 1900);
FORCEPROP 2 LAST P1V5_STBY_IBMC_VR 
J 0
(7075 1850);
PAINT GREEN (7075 1850);
FORCEPROP 2 LAST ROOM P1V26_BMC_STBY_VR
J 0
(6700 1850);
DISPLAY 0.872340 (6700 1850);
PAINT GREEN (6700 1850);
DISPLAY INVISIBLE (6700 1850);
FORCEPROP 1 LAST VOLTAGE 0.0V
J 0
(7005 1732);
DISPLAY 0.340426 (7005 1732);
PAINT SKYBLUE (7005 1732);
DISPLAY INVISIBLE (7005 1732);
FORCEPROP 1 LAST SIZE 1B
J 0
(7125 1725);
DISPLAY 0.872340 (7125 1725);
PAINT ORANGE (7125 1725);
DISPLAY INVISIBLE (7125 1725);
FORCEPROP 2 LAST BOM_COST P1V26_BMC_STBY_VR
J 0
(7075 1950);
PAINT WHITE (7075 1950);
DISPLAY INVISIBLE (7075 1950);
FORCEPROP 1 LAST PATH I74
J 0
(7125 1775);
DISPLAY 0.872340 (7125 1775);
PAINT AQUA (7125 1775);
DISPLAY INVISIBLE (7125 1775);
FORCEPROP 2 LAST CDS_LIB mstr_symbols
J 0
(7050 1775);
PAINT MONO (7050 1775);
DISPLAY INVISIBLE (7050 1775);
FORCEPROP 1 LAST BODY_TYPE PLUMBING
J 0
(7005 1732);
DISPLAY 0.340426 (7005 1732);
PAINT GREEN (7005 1732);
DISPLAY INVISIBLE (7005 1732);
FORCEPROP 1 LAST HDL_POWER GND
J 0
(7050 1925);
DISPLAY 0.872340 (7050 1925);
PAINT GREEN (7050 1925);
DISPLAY INVISIBLE (7050 1925);
FORCEADD P3V3_STBY..1
(6100 2550);
FORCEPROP 3 LASTPIN (6100 2500) SIG_NAME P3V3_STBY\g
J 0
(6110 2510);
DISPLAY 0.659574 (6110 2510);
PAINT MONO (6110 2510);
DISPLAY INVISIBLE (6110 2510);
FORCEPROP 1 LAST VOLTAGE 3.3V
J 0
(6055 2507);
DISPLAY 0.340426 (6055 2507);
PAINT SKYBLUE (6055 2507);
DISPLAY INVISIBLE (6055 2507);
FORCEPROP 1 LAST SIZE 1B
J 0
(6145 2572);
DISPLAY 0.340426 (6145 2572);
PAINT GREEN (6145 2572);
DISPLAY INVISIBLE (6145 2572);
FORCEPROP 1 LAST PATH I75
J 0
(6145 2552);
DISPLAY 0.340426 (6145 2552);
PAINT GREEN (6145 2552);
DISPLAY INVISIBLE (6145 2552);
FORCEPROP 2 LAST CDS_LIB mstr_symbols
J 0
(6100 2550);
PAINT MONO (6100 2550);
DISPLAY INVISIBLE (6100 2550);
FORCEPROP 1 LAST BODY_TYPE PLUMBING
J 0
(6055 2507);
DISPLAY 0.340426 (6055 2507);
PAINT GREEN (6055 2507);
DISPLAY INVISIBLE (6055 2507);
FORCEPROP 1 LAST HDL_POWER P3V3_STBY
J 0
(5800 2425);
DISPLAY 0.872340 (5800 2425);
PAINT ORANGE (5800 2425);
DISPLAY INVISIBLE (5800 2425);
FORCEADD OFFPAGE..2
(11125 2200);
FORCEPROP 2 LAST PATH I76
J 0
(11300 2275);
DISPLAY 1.021277 (11300 2275);
PAINT ORANGE (11300 2275);
DISPLAY INVISIBLE (11300 2275);
FORCEPROP 2 LAST CDS_LIB mstr_standard
J 0
(11125 2200);
PAINT MONO (11125 2200);
DISPLAY INVISIBLE (11125 2200);
FORCEPROP 2 LASTPIN (11075 2200) SIG_NAME UN$239$OFFPAGE$I76$A
J 0
(11085 2210);
DISPLAY 0.659574 (11085 2210);
PAINT MONO (11085 2210);
DISPLAY INVISIBLE (11085 2210);
FORCEPROP 1 LAST OFFPAGE TRUE
J 0
(11450 2075);
DISPLAY 0.872340 (11450 2075);
PAINT GREEN (11450 2075);
DISPLAY INVISIBLE (11450 2075);
FORCEPROP 1 LAST COMMENT_BODY TRUE
J 0
(11080 2105);
DISPLAY 0.872340 (11080 2105);
PAINT GREEN (11080 2105);
DISPLAY INVISIBLE (11080 2105);
FORCEADD RES..1
(10275 2200);
FORCEPROP 1 LAST PACK_TYPE 0402
J 0
(10525 2050);
DISPLAY 0.617021 (10525 2050);
PAINT SKYBLUE (10525 2050);
FORCEPROP 1 LAST WATTAGE 1/16W
J 2
(10250 2050);
DISPLAY 0.617021 (10250 2050);
PAINT SKYBLUE (10250 2050);
FORCEPROP 1 LAST TOLERANCE 1.0%
J 0
(10275 2100);
DISPLAY 0.617021 (10275 2100);
PAINT SKYBLUE (10275 2100);
FORCEPROP 1 LAST LOCATION R1W9
J 0
(10225 2250);
DISPLAY 0.617021 (10225 2250);
PAINT AQUA (10225 2250);
FORCEPROP 1 LAST VALUE 22.1
J 2
(10250 2100);
DISPLAY 0.617021 (10250 2100);
PAINT SKYBLUE (10250 2100);
FORCEPROP 1 LAST MATERIAL CHIP
J 0
(10275 2050);
DISPLAY 0.617021 (10275 2050);
PAINT SKYBLUE (10275 2050);
FORCEPROP 1 LAST PART_NUMBER G21796-250
J 0
(10225 2300);
DISPLAY 0.617021 (10225 2300);
PAINT BLUE (10225 2300);
FORCEPROP 1 LASTPIN (10375 2200) $PN 2
J 0
(10337 2212);
DISPLAY 0.787234 (10337 2212);
PAINT ORANGE (10337 2212);
DISPLAY INVISIBLE (10337 2212);
FORCEPROP 1 LASTPIN (10175 2200) $PN 1
J 0
(10187 2212);
DISPLAY 0.787234 (10187 2212);
PAINT ORANGE (10187 2212);
DISPLAY INVISIBLE (10187 2212);
FORCEPROP 0 LAST ROOM P1V538_BMC_STBY_VR
J 0
(10225 2400);
DISPLAY 1.021277 (10225 2400);
PAINT ORANGE (10225 2400);
DISPLAY INVISIBLE (10225 2400);
FORCEPROP 1 LAST PATH I77
J 0
(10225 2350);
DISPLAY 0.978723 (10225 2350);
PAINT WHITE (10225 2350);
DISPLAY INVISIBLE (10225 2350);
FORCEPROP 2 LAST CDS_LIB mstr_discrete
J 0
(10275 2200);
PAINT MONO (10275 2200);
DISPLAY INVISIBLE (10275 2200);
FORCEADD P3V3_STBY..1
(9200 2700);
FORCEPROP 3 LASTPIN (9200 2650) SIG_NAME P3V3_STBY\g
J 0
(9210 2660);
DISPLAY 0.659574 (9210 2660);
PAINT MONO (9210 2660);
DISPLAY INVISIBLE (9210 2660);
FORCEPROP 1 LAST SIZE 1B
J 0
(9245 2722);
DISPLAY 0.340426 (9245 2722);
PAINT GREEN (9245 2722);
DISPLAY INVISIBLE (9245 2722);
FORCEPROP 1 LAST VOLTAGE 3.3V
J 0
(9155 2657);
DISPLAY 0.340426 (9155 2657);
PAINT SKYBLUE (9155 2657);
DISPLAY INVISIBLE (9155 2657);
FORCEPROP 1 LAST PATH I78
J 0
(9245 2702);
DISPLAY 0.340426 (9245 2702);
PAINT GREEN (9245 2702);
DISPLAY INVISIBLE (9245 2702);
FORCEPROP 2 LAST CDS_LIB mstr_symbols
J 0
(9200 2700);
PAINT MONO (9200 2700);
DISPLAY INVISIBLE (9200 2700);
FORCEPROP 1 LAST BODY_TYPE PLUMBING
J 0
(9155 2657);
DISPLAY 0.340426 (9155 2657);
PAINT GREEN (9155 2657);
DISPLAY INVISIBLE (9155 2657);
FORCEPROP 1 LAST HDL_POWER P3V3_STBY
J 0
(8900 2575);
DISPLAY 0.872340 (8900 2575);
PAINT ORANGE (8900 2575);
DISPLAY INVISIBLE (8900 2575);
FORCEADD RES..2
(9200 2450);
FORCEPROP 1 LAST LOCATION R9W12
J 0
(9245 2575);
DISPLAY 0.617021 (9245 2575);
PAINT AQUA (9245 2575);
FORCEPROP 2 LAST P1V5_STBY_IBMC_VR 
J 0
(9150 2600);
PAINT GREEN (9150 2600);
FORCEPROP 2 LAST P1V5_STBY_IBMC 
J 0
(9150 2650);
PAINT GREEN (9150 2650);
FORCEPROP 1 LAST VALUE 10.0K
J 0
(9245 2525);
DISPLAY 0.617021 (9245 2525);
PAINT SKYBLUE (9245 2525);
FORCEPROP 1 LAST TOLERANCE 1%
J 0
(9245 2475);
DISPLAY 0.617021 (9245 2475);
PAINT SKYBLUE (9245 2475);
FORCEPROP 1 LAST WATTAGE 1/16W
J 0
(9240 2425);
DISPLAY 0.617021 (9240 2425);
PAINT SKYBLUE (9240 2425);
FORCEPROP 1 LAST MATERIAL CHIP
J 0
(9240 2375);
DISPLAY 0.617021 (9240 2375);
PAINT SKYBLUE (9240 2375);
FORCEPROP 1 LAST PACK_TYPE 0402
J 0
(9240 2275);
DISPLAY 0.617021 (9240 2275);
PAINT SKYBLUE (9240 2275);
FORCEPROP 1 LAST PART_NUMBER G21796-016
J 0
(9240 2325);
DISPLAY 0.617021 (9240 2325);
PAINT BLUE (9240 2325);
FORCEPROP 1 LASTPIN (9200 2550) $PN 1
J 0
(9205 2512);
DISPLAY 0.787234 (9205 2512);
PAINT ORANGE (9205 2512);
DISPLAY INVISIBLE (9205 2512);
FORCEPROP 1 LASTPIN (9200 2350) $PN 2
J 0
(9205 2360);
DISPLAY 0.787234 (9205 2360);
PAINT ORANGE (9205 2360);
DISPLAY INVISIBLE (9205 2360);
FORCEPROP 2 LAST ROOM P1V538_BMC_STBY_VR
J 0
(9150 2550);
PAINT GREEN (9150 2550);
DISPLAY INVISIBLE (9150 2550);
FORCEPROP 2 LAST BOM_COST P1V538_BMC_STBY_VR
J 0
(9150 2700);
PAINT WHITE (9150 2700);
DISPLAY INVISIBLE (9150 2700);
FORCEPROP 1 LAST PATH I79
J 0
(9250 2625);
DISPLAY 0.978723 (9250 2625);
PAINT WHITE (9250 2625);
DISPLAY INVISIBLE (9250 2625);
FORCEPROP 2 LAST CDS_LIB mstr_discrete
J 0
(9200 2450);
PAINT MONO (9200 2450);
DISPLAY INVISIBLE (9200 2450);
FORCEADD CAP..1
(10875 1475);
FORCEPROP 1 LAST LOCATION C9W13
J 0
(10925 1575);
DISPLAY 0.617021 (10925 1575);
PAINT AQUA (10925 1575);
FORCEPROP 1 LAST TOLERANCE 20%
J 0
(10925 1425);
DISPLAY 0.617021 (10925 1425);
PAINT SKYBLUE (10925 1425);
FORCEPROP 1 LAST PART_NUMBER C95333-002
J 0
(10925 1325);
DISPLAY 0.617021 (10925 1325);
PAINT BLUE (10925 1325);
FORCEPROP 1 LAST MATERIAL X6S
J 0
(10925 1375);
DISPLAY 0.617021 (10925 1375);
PAINT SKYBLUE (10925 1375);
FORCEPROP 1 LAST PACK_TYPE 0805LF
J 0
(10925 1275);
DISPLAY 0.617021 (10925 1275);
PAINT SKYBLUE (10925 1275);
FORCEPROP 1 LAST VOLTAGE 4V
J 0
(10925 1475);
DISPLAY 0.617021 (10925 1475);
PAINT SKYBLUE (10925 1475);
FORCEPROP 1 LAST VALUE 22UF
J 0
(10925 1525);
DISPLAY 0.617021 (10925 1525);
PAINT SKYBLUE (10925 1525);
FORCEPROP 1 LASTPIN (10875 1575) $PN 1
J 0
(10885 1555);
DISPLAY 0.787234 (10885 1555);
PAINT ORANGE (10885 1555);
DISPLAY INVISIBLE (10885 1555);
FORCEPROP 1 LASTPIN (10875 1375) $PN 2
J 0
(10885 1355);
DISPLAY 0.787234 (10885 1355);
PAINT ORANGE (10885 1355);
DISPLAY INVISIBLE (10885 1355);
FORCEPROP 2 LAST BOM_COST P1V538_BMC_STBY_VR
J 0
(10925 1625);
PAINT WHITE (10925 1625);
DISPLAY INVISIBLE (10925 1625);
FORCEPROP 2 LAST ROOM P1V538_BMC_STBY_VR
J 0
(10925 1675);
PAINT GREEN (10925 1675);
DISPLAY INVISIBLE (10925 1675);
FORCEPROP 1 LAST PATH I81
J 0
(10925 1625);
DISPLAY 0.978723 (10925 1625);
PAINT WHITE (10925 1625);
DISPLAY INVISIBLE (10925 1625);
FORCEPROP 2 LAST CDS_LIB mstr_discrete
J 0
(10875 1475);
PAINT MONO (10875 1475);
DISPLAY INVISIBLE (10875 1475);
FORCEADD GND..1
(10750 1125);
FORCEPROP 3 LASTPIN (10750 1175) SIG_NAME GND\g
J 0
(10760 1185);
DISPLAY 0.659574 (10760 1185);
PAINT MONO (10760 1185);
DISPLAY INVISIBLE (10760 1185);
FORCEPROP 2 LAST P1V5_STBY_IBMC_VR 
J 0
(10775 1200);
PAINT GREEN (10775 1200);
FORCEPROP 2 LAST P1V5_STBY_IBMC 
J 0
(10775 1250);
PAINT GREEN (10775 1250);
FORCEPROP 2 LAST ROOM P1V538_BMC_STBY_VR
J 0
(10400 1200);
DISPLAY 0.872340 (10400 1200);
PAINT GREEN (10400 1200);
DISPLAY INVISIBLE (10400 1200);
FORCEPROP 1 LAST VOLTAGE 0.0V
J 0
(10705 1082);
DISPLAY 0.340426 (10705 1082);
PAINT SKYBLUE (10705 1082);
DISPLAY INVISIBLE (10705 1082);
FORCEPROP 1 LAST SIZE 1B
J 0
(10825 1075);
DISPLAY 0.872340 (10825 1075);
PAINT ORANGE (10825 1075);
DISPLAY INVISIBLE (10825 1075);
FORCEPROP 2 LAST BOM_COST P1V538_BMC_STBY_VR
J 0
(10775 1300);
PAINT WHITE (10775 1300);
DISPLAY INVISIBLE (10775 1300);
FORCEPROP 1 LAST PATH I82
J 0
(10825 1125);
DISPLAY 0.872340 (10825 1125);
PAINT AQUA (10825 1125);
DISPLAY INVISIBLE (10825 1125);
FORCEPROP 2 LAST CDS_LIB mstr_symbols
J 0
(10750 1125);
PAINT MONO (10750 1125);
DISPLAY INVISIBLE (10750 1125);
FORCEPROP 1 LAST BODY_TYPE PLUMBING
J 0
(10705 1082);
DISPLAY 0.340426 (10705 1082);
PAINT GREEN (10705 1082);
DISPLAY INVISIBLE (10705 1082);
FORCEPROP 1 LAST HDL_POWER GND
J 0
(10750 1275);
DISPLAY 0.872340 (10750 1275);
PAINT GREEN (10750 1275);
DISPLAY INVISIBLE (10750 1275);
FORCEADD CAP..1
(10450 1550);
FORCEPROP 1 LAST PACK_TYPE 0603
J 0
(10500 1350);
DISPLAY 0.617021 (10500 1350);
PAINT SKYBLUE (10500 1350);
FORCEPROP 1 LAST PART_NUMBER E15431-002
J 0
(10500 1400);
DISPLAY 0.617021 (10500 1400);
PAINT BLUE (10500 1400);
FORCEPROP 1 LAST VOLTAGE 6.3V
J 0
(10500 1550);
DISPLAY 0.617021 (10500 1550);
PAINT SKYBLUE (10500 1550);
FORCEPROP 1 LAST TOLERANCE 20%
J 0
(10500 1500);
DISPLAY 0.617021 (10500 1500);
PAINT SKYBLUE (10500 1500);
FORCEPROP 1 LAST MATERIAL X6S
J 0
(10500 1450);
DISPLAY 0.617021 (10500 1450);
PAINT SKYBLUE (10500 1450);
FORCEPROP 1 LAST VALUE 10UF
J 0
(10500 1600);
DISPLAY 0.617021 (10500 1600);
PAINT SKYBLUE (10500 1600);
FORCEPROP 1 LAST LOCATION C1W15
J 0
(10500 1650);
DISPLAY 0.617021 (10500 1650);
PAINT AQUA (10500 1650);
FORCEPROP 1 LASTPIN (10450 1650) $PN 1
J 0
(10460 1630);
DISPLAY 0.787234 (10460 1630);
PAINT ORANGE (10460 1630);
DISPLAY INVISIBLE (10460 1630);
FORCEPROP 1 LASTPIN (10450 1450) $PN 2
J 0
(10460 1430);
DISPLAY 0.787234 (10460 1430);
PAINT ORANGE (10460 1430);
DISPLAY INVISIBLE (10460 1430);
FORCEPROP 2 LAST BOM_COST P1V538_BMC_STBY_VR
J 0
(10500 1700);
PAINT WHITE (10500 1700);
DISPLAY INVISIBLE (10500 1700);
FORCEPROP 2 LAST ROOM P1V538_BMC_STBY_VR
J 0
(10500 1750);
PAINT GREEN (10500 1750);
DISPLAY INVISIBLE (10500 1750);
FORCEPROP 1 LAST PATH I83
J 0
(10500 1700);
DISPLAY 0.978723 (10500 1700);
PAINT WHITE (10500 1700);
DISPLAY INVISIBLE (10500 1700);
FORCEPROP 2 LAST CDS_LIB mstr_discrete
J 0
(10450 1550);
PAINT MONO (10450 1550);
DISPLAY INVISIBLE (10450 1550);
FORCEADD CAP..1
(9950 2075);
FORCEPROP 1 LAST MATERIAL X7R
J 0
(10000 1975);
DISPLAY 0.617021 (10000 1975);
PAINT SKYBLUE (10000 1975);
FORCEPROP 1 LAST TOLERANCE 10%
J 0
(10000 2025);
DISPLAY 0.617021 (10000 2025);
PAINT SKYBLUE (10000 2025);
FORCEPROP 1 LAST PACK_TYPE 0402LF
J 0
(10000 1875);
DISPLAY 0.617021 (10000 1875);
PAINT SKYBLUE (10000 1875);
FORCEPROP 1 LAST LOCATION C9W10
J 0
(9825 2150);
DISPLAY 0.617021 (9825 2150);
PAINT AQUA (9825 2150);
FORCEPROP 1 LAST VALUE 1000PF
J 0
(10000 2125);
DISPLAY 0.617021 (10000 2125);
PAINT SKYBLUE (10000 2125);
FORCEPROP 1 LAST PART_NUMBER A36096-046
J 0
(10000 1000);
DISPLAY 0.617021 (10000 1000);
PAINT BLUE (10000 1000);
FORCEPROP 1 LASTPIN (9950 2175) $PN 1
J 0
(9960 2155);
DISPLAY 0.787234 (9960 2155);
PAINT ORANGE (9960 2155);
DISPLAY INVISIBLE (9960 2155);
FORCEPROP 1 LASTPIN (9950 1975) $PN 2
J 0
(9960 1955);
DISPLAY 0.787234 (9960 1955);
PAINT ORANGE (9960 1955);
DISPLAY INVISIBLE (9960 1955);
FORCEPROP 2 LAST ROOM P1V538_BMC_STBY_VR
J 0
(10010 2215);
DISPLAY 1.617021 (10010 2215);
PAINT GREEN (10010 2215);
DISPLAY INVISIBLE (10010 2215);
FORCEPROP 2 LAST BOM_COST P1V538_BMC_STBY_VR
J 0
(10010 2215);
DISPLAY 1.617021 (10010 2215);
PAINT WHITE (10010 2215);
DISPLAY INVISIBLE (10010 2215);
FORCEPROP 1 LAST VOLTAGE 50V
J 0
(10000 2075);
DISPLAY 1.617021 (10000 2075);
PAINT SKYBLUE (10000 2075);
DISPLAY INVISIBLE (10000 2075);
FORCEPROP 1 LAST PATH I84
J 0
(10000 2225);
DISPLAY 0.978723 (10000 2225);
PAINT WHITE (10000 2225);
DISPLAY INVISIBLE (10000 2225);
FORCEPROP 2 LAST CDS_LIB mstr_discrete
J 0
(9950 2075);
PAINT MONO (9950 2075);
DISPLAY INVISIBLE (9950 2075);
FORCEPROP 2 LASTPIN (9950 2175) SIG_NAME UN$239$CAP$I84$A
J 0
(9960 2185);
DISPLAY 0.659574 (9960 2185);
PAINT MONO (9960 2185);
DISPLAY INVISIBLE (9960 2185);
FORCEADD GND..1
(9950 1900);
FORCEPROP 3 LASTPIN (9950 1950) SIG_NAME GND\g
J 0
(9960 1960);
DISPLAY 0.659574 (9960 1960);
PAINT MONO (9960 1960);
DISPLAY INVISIBLE (9960 1960);
FORCEPROP 2 LAST ROOM P1V538_BMC_STBY_VR
J 0
(9300 1975);
DISPLAY 1.212766 (9300 1975);
PAINT GREEN (9300 1975);
DISPLAY INVISIBLE (9300 1975);
FORCEPROP 1 LAST VOLTAGE 0.0V
J 0
(9905 1857);
DISPLAY 0.340426 (9905 1857);
PAINT SKYBLUE (9905 1857);
DISPLAY INVISIBLE (9905 1857);
FORCEPROP 1 LAST SIZE 1B
J 0
(10025 1850);
DISPLAY 1.063830 (10025 1850);
PAINT GREEN (10025 1850);
DISPLAY INVISIBLE (10025 1850);
FORCEPROP 2 LAST BOM_COST P1V538_BMC_STBY_VR
J 0
(9635 1990);
DISPLAY 1.617021 (9635 1990);
PAINT WHITE (9635 1990);
DISPLAY INVISIBLE (9635 1990);
FORCEPROP 1 LAST PATH I85
J 0
(10025 1900);
DISPLAY 0.872340 (10025 1900);
PAINT AQUA (10025 1900);
DISPLAY INVISIBLE (10025 1900);
FORCEPROP 2 LAST CDS_LIB mstr_symbols
J 0
(9950 1900);
PAINT MONO (9950 1900);
DISPLAY INVISIBLE (9950 1900);
FORCEPROP 1 LAST BODY_TYPE PLUMBING
J 0
(9905 1857);
DISPLAY 0.340426 (9905 1857);
PAINT GREEN (9905 1857);
DISPLAY INVISIBLE (9905 1857);
FORCEPROP 1 LAST HDL_POWER GND
J 0
(9950 2050);
DISPLAY 1.063830 (9950 2050);
PAINT GREEN (9950 2050);
DISPLAY INVISIBLE (9950 2050);
FORCEADD RES..1
R 1
(9925 900);
FORCEPROP 1 LAST MATERIAL CHIP
J 0
(10000 825);
DISPLAY 0.617021 (10000 825);
PAINT SKYBLUE (10000 825);
FORCEPROP 2 LAST P1V5_STBY_IBMC 
J 0
(9975 1150);
PAINT GREEN (9975 1150);
FORCEPROP 2 LAST P1V5_STBY_IBMC_VR 
J 0
(9975 1100);
PAINT GREEN (9975 1100);
FORCEPROP 1 LAST TOLERANCE 1.0%
J 0
(10125 825);
DISPLAY 0.617021 (10125 825);
PAINT SKYBLUE (10125 825);
FORCEPROP 1 LAST VALUE 13K
J 2
(10075 875);
DISPLAY 0.617021 (10075 875);
PAINT SKYBLUE (10075 875);
FORCEPROP 1 LAST LOCATION R9W32
J 0
(10000 925);
DISPLAY 0.617021 (10000 925);
PAINT AQUA (10000 925);
FORCEPROP 1 LAST PACK_TYPE 0402
J 0
(10025 725);
DISPLAY 0.617021 (10025 725);
PAINT SKYBLUE (10025 725);
FORCEPROP 1 LAST PART_NUMBER G21796-221
J 0
(10000 775);
DISPLAY 0.617021 (10000 775);
PAINT BLUE (10000 775);
FORCEPROP 1 LAST WATTAGE 1/16W
J 2
(10400 825);
DISPLAY 0.617021 (10400 825);
PAINT SKYBLUE (10400 825);
FORCEPROP 1 LASTPIN (9925 1000) $PN 2
R 1
J 0
(9913 962);
DISPLAY 0.787234 (9913 962);
PAINT ORANGE (9913 962);
DISPLAY INVISIBLE (9913 962);
FORCEPROP 1 LASTPIN (9925 800) $PN 1
R 1
J 0
(9913 812);
DISPLAY 0.787234 (9913 812);
PAINT ORANGE (9913 812);
DISPLAY INVISIBLE (9913 812);
FORCEPROP 2 LAST BOM_COST P1V538_BMC_STBY_VR
J 0
(9975 1200);
PAINT WHITE (9975 1200);
DISPLAY INVISIBLE (9975 1200);
FORCEPROP 2 LAST ROOM P1V538_BMC_STBY_VR
J 0
(9975 1050);
PAINT GREEN (9975 1050);
DISPLAY INVISIBLE (9975 1050);
FORCEPROP 1 LAST PATH I87
R 1
J 0
(9775 850);
DISPLAY 0.978723 (9775 850);
PAINT WHITE (9775 850);
DISPLAY INVISIBLE (9775 850);
FORCEPROP 2 LAST CDS_LIB mstr_discrete
J 0
(9925 900);
PAINT MONO (9925 900);
DISPLAY INVISIBLE (9925 900);
FORCEADD GND..1
(9925 625);
FORCEPROP 3 LASTPIN (9925 675) SIG_NAME GND\g
J 0
(9935 685);
DISPLAY 0.659574 (9935 685);
PAINT MONO (9935 685);
DISPLAY INVISIBLE (9935 685);
FORCEPROP 2 LAST P1V5_STBY_IBMC 
J 0
(9950 750);
PAINT GREEN (9950 750);
FORCEPROP 2 LAST P1V5_STBY_IBMC_VR 
J 0
(9950 700);
PAINT GREEN (9950 700);
FORCEPROP 2 LAST BOM_COST P1V538_BMC_STBY_VR
J 0
(9950 800);
PAINT WHITE (9950 800);
DISPLAY INVISIBLE (9950 800);
FORCEPROP 1 LAST SIZE 1B
J 0
(10000 575);
DISPLAY 0.872340 (10000 575);
PAINT ORANGE (10000 575);
DISPLAY INVISIBLE (10000 575);
FORCEPROP 1 LAST VOLTAGE 0.0V
J 0
(9880 582);
DISPLAY 0.340426 (9880 582);
PAINT SKYBLUE (9880 582);
DISPLAY INVISIBLE (9880 582);
FORCEPROP 2 LAST ROOM P1V538_BMC_STBY_VR
J 0
(9575 700);
DISPLAY 0.872340 (9575 700);
PAINT GREEN (9575 700);
DISPLAY INVISIBLE (9575 700);
FORCEPROP 1 LAST PATH I88
J 0
(10000 625);
DISPLAY 0.872340 (10000 625);
PAINT AQUA (10000 625);
DISPLAY INVISIBLE (10000 625);
FORCEPROP 2 LAST CDS_LIB mstr_symbols
J 0
(9925 625);
PAINT MONO (9925 625);
DISPLAY INVISIBLE (9925 625);
FORCEPROP 1 LAST BODY_TYPE PLUMBING
J 0
(9880 582);
DISPLAY 0.340426 (9880 582);
PAINT GREEN (9880 582);
DISPLAY INVISIBLE (9880 582);
FORCEPROP 1 LAST HDL_POWER GND
J 0
(9925 775);
DISPLAY 0.872340 (9925 775);
PAINT GREEN (9925 775);
DISPLAY INVISIBLE (9925 775);
FORCEADD GND..1
(9025 1275);
FORCEPROP 3 LASTPIN (9025 1325) SIG_NAME GND\g
J 0
(9035 1335);
DISPLAY 0.659574 (9035 1335);
PAINT MONO (9035 1335);
DISPLAY INVISIBLE (9035 1335);
FORCEPROP 2 LAST P1V5_STBY_IBMC 
J 0
(9050 1400);
PAINT GREEN (9050 1400);
FORCEPROP 2 LAST P1V5_STBY_IBMC_VR 
J 0
(9050 1350);
PAINT GREEN (9050 1350);
FORCEPROP 2 LAST ROOM P1V26_BMC_STBY_VR
J 0
(8675 1350);
DISPLAY 0.872340 (8675 1350);
PAINT GREEN (8675 1350);
DISPLAY INVISIBLE (8675 1350);
FORCEPROP 1 LAST VOLTAGE 0.0V
J 0
(8980 1232);
DISPLAY 0.340426 (8980 1232);
PAINT SKYBLUE (8980 1232);
DISPLAY INVISIBLE (8980 1232);
FORCEPROP 2 LAST BOM_COST P1V26_BMC_STBY_VR
J 0
(9050 1450);
PAINT WHITE (9050 1450);
DISPLAY INVISIBLE (9050 1450);
FORCEPROP 1 LAST SIZE 1B
J 0
(9100 1225);
DISPLAY 0.872340 (9100 1225);
PAINT ORANGE (9100 1225);
DISPLAY INVISIBLE (9100 1225);
FORCEPROP 1 LAST PATH I89
J 0
(9100 1275);
DISPLAY 0.872340 (9100 1275);
PAINT AQUA (9100 1275);
DISPLAY INVISIBLE (9100 1275);
FORCEPROP 2 LAST CDS_LIB mstr_symbols
J 0
(9025 1275);
PAINT MONO (9025 1275);
DISPLAY INVISIBLE (9025 1275);
FORCEPROP 1 LAST BODY_TYPE PLUMBING
J 0
(8980 1232);
DISPLAY 0.340426 (8980 1232);
PAINT GREEN (8980 1232);
DISPLAY INVISIBLE (8980 1232);
FORCEPROP 1 LAST HDL_POWER GND
J 0
(9025 1425);
DISPLAY 0.872340 (9025 1425);
PAINT GREEN (9025 1425);
DISPLAY INVISIBLE (9025 1425);
FORCEADD GND..1
(11175 3200);
FORCEPROP 3 LASTPIN (11175 3250) SIG_NAME GND\g
J 0
(11185 3260);
DISPLAY 0.659574 (11185 3260);
PAINT MONO (11185 3260);
DISPLAY INVISIBLE (11185 3260);
FORCEPROP 2 LAST P1V5_STBY_IBMC 
J 0
(11200 3325);
PAINT GREEN (11200 3325);
FORCEPROP 2 LAST P1V5_STBY_IBMC_VR 
J 0
(11200 3275);
PAINT GREEN (11200 3275);
FORCEPROP 2 LAST CDS_LIB mstr_symbols
J 0
(11175 3200);
PAINT ORANGE (11175 3200);
DISPLAY INVISIBLE (11175 3200);
FORCEPROP 1 LAST PATH I9
J 0
(11250 3200);
DISPLAY 0.872340 (11250 3200);
PAINT AQUA (11250 3200);
DISPLAY INVISIBLE (11250 3200);
FORCEPROP 2 LAST BOM_COST P1V538_BMC_STBY_VR
J 0
(11200 3375);
PAINT WHITE (11200 3375);
DISPLAY INVISIBLE (11200 3375);
FORCEPROP 1 LAST SIZE 1B
J 0
(11250 3150);
DISPLAY 0.872340 (11250 3150);
PAINT ORANGE (11250 3150);
DISPLAY INVISIBLE (11250 3150);
FORCEPROP 1 LAST VOLTAGE 0.0V
J 0
(11130 3157);
DISPLAY 0.340426 (11130 3157);
PAINT SKYBLUE (11130 3157);
DISPLAY INVISIBLE (11130 3157);
FORCEPROP 2 LAST ROOM P1V538_BMC_STBY_VR
J 0
(10825 3275);
DISPLAY 0.872340 (10825 3275);
PAINT GREEN (10825 3275);
DISPLAY INVISIBLE (10825 3275);
FORCEPROP 1 LAST BODY_TYPE PLUMBING
J 0
(11130 3157);
DISPLAY 0.340426 (11130 3157);
PAINT GREEN (11130 3157);
DISPLAY INVISIBLE (11130 3157);
FORCEPROP 1 LAST HDL_POWER GND
J 0
(11175 3350);
DISPLAY 0.872340 (11175 3350);
PAINT GREEN (11175 3350);
DISPLAY INVISIBLE (11175 3350);
FORCEADD CAP_A..1
(7050 2050);
FORCEPROP 1 LAST MATERIAL X7R
J 0
(7100 1950);
DISPLAY 0.617021 (7100 1950);
PAINT SKYBLUE (7100 1950);
FORCEPROP 1 LAST VALUE 0.1UF
J 0
(7100 2100);
DISPLAY 0.617021 (7100 2100);
PAINT SKYBLUE (7100 2100);
FORCEPROP 1 LAST VOLTAGE 16V
J 0
(7100 2050);
DISPLAY 0.617021 (7100 2050);
PAINT SKYBLUE (7100 2050);
FORCEPROP 1 LAST TOLERANCE 10%
J 0
(7100 2000);
DISPLAY 0.617021 (7100 2000);
PAINT SKYBLUE (7100 2000);
FORCEPROP 1 LAST PACK_TYPE 0402V
J 0
(7100 1850);
DISPLAY 0.617021 (7100 1850);
PAINT SKYBLUE (7100 1850);
FORCEPROP 1 LAST PART_NUMBER A36096-030
J 0
(7100 1900);
DISPLAY 0.617021 (7100 1900);
PAINT BLUE (7100 1900);
FORCEPROP 1 LAST LOCATION C9W5
J 0
(7100 2150);
DISPLAY 0.617021 (7100 2150);
PAINT AQUA (7100 2150);
FORCEPROP 1 LASTPIN (7050 1950) $PN 2
J 0
(7060 1930);
DISPLAY 0.787234 (7060 1930);
PAINT ORANGE (7060 1930);
DISPLAY INVISIBLE (7060 1930);
FORCEPROP 1 LASTPIN (7050 2150) $PN 1
J 0
(7060 2130);
DISPLAY 0.787234 (7060 2130);
PAINT ORANGE (7060 2130);
DISPLAY INVISIBLE (7060 2130);
FORCEPROP 1 LAST PATH I90
J 0
(7100 2200);
DISPLAY 0.978723 (7100 2200);
PAINT WHITE (7100 2200);
DISPLAY INVISIBLE (7100 2200);
FORCEPROP 2 LAST CDS_LIB dev_discrete
J 0
(7050 2050);
PAINT MONO (7050 2050);
DISPLAY INVISIBLE (7050 2050);
FORCEADD CAP..1
R 2
(6625 1225);
FORCEPROP 1 LAST PART_NUMBER A36096-046
J 2
(6575 1075);
DISPLAY 0.617021 (6575 1075);
PAINT BLUE (6575 1075);
FORCEPROP 1 LAST PACK_TYPE 0402LF
J 2
(6450 1175);
DISPLAY 0.617021 (6450 1175);
PAINT SKYBLUE (6450 1175);
FORCEPROP 1 LAST TOLERANCE 10%
J 2
(6575 1175);
DISPLAY 0.617021 (6575 1175);
PAINT SKYBLUE (6575 1175);
FORCEPROP 1 LAST VOLTAGE 50V
J 2
(6575 1225);
DISPLAY 0.617021 (6575 1225);
PAINT SKYBLUE (6575 1225);
FORCEPROP 1 LAST MATERIAL EMPTY
J 2
(6575 1125);
DISPLAY 0.617021 (6575 1125);
PAINT RED (6575 1125);
FORCEPROP 1 LAST VALUE 1000PF
J 2
(6475 1250);
DISPLAY 0.617021 (6475 1250);
PAINT SKYBLUE (6475 1250);
FORCEPROP 1 LAST LOCATION C9W6
J 2
(6450 1300);
DISPLAY 0.617021 (6450 1300);
PAINT AQUA (6450 1300);
FORCEPROP 1 LASTPIN (6625 1325) $PN 1
J 2
(6615 1305);
DISPLAY 0.787234 (6615 1305);
PAINT ORANGE (6615 1305);
DISPLAY INVISIBLE (6615 1305);
FORCEPROP 1 LASTPIN (6625 1125) $PN 2
J 2
(6615 1105);
DISPLAY 0.787234 (6615 1105);
PAINT ORANGE (6615 1105);
DISPLAY INVISIBLE (6615 1105);
FORCEPROP 2 LAST BOM_COST P1V538_BMC_STBY_VR
J 0
(6560 1335);
DISPLAY 1.617021 (6560 1335);
PAINT WHITE (6560 1335);
DISPLAY INVISIBLE (6560 1335);
FORCEPROP 2 LAST ROOM P1V538_BMC_STBY_VR
J 2
(6575 1350);
DISPLAY 1.212766 (6575 1350);
PAINT GREEN (6575 1350);
DISPLAY INVISIBLE (6575 1350);
FORCEPROP 1 LAST PATH I91
J 2
(6575 1375);
DISPLAY 0.978723 (6575 1375);
PAINT WHITE (6575 1375);
DISPLAY INVISIBLE (6575 1375);
FORCEPROP 2 LAST CDS_LIB mstr_discrete
J 0
(6625 1225);
PAINT MONO (6625 1225);
DISPLAY INVISIBLE (6625 1225);
FORCEADD CAP..1
(6100 2075);
FORCEPROP 1 LAST LOCATION C1W7
J 0
(6150 2175);
DISPLAY 0.617021 (6150 2175);
PAINT AQUA (6150 2175);
FORCEPROP 1 LAST PART_NUMBER E15431-002
J 0
(6150 1925);
DISPLAY 0.617021 (6150 1925);
PAINT BLUE (6150 1925);
FORCEPROP 1 LAST VALUE 10UF
J 0
(6150 2125);
DISPLAY 0.617021 (6150 2125);
PAINT SKYBLUE (6150 2125);
FORCEPROP 1 LAST MATERIAL X6S
J 0
(6150 1975);
DISPLAY 0.617021 (6150 1975);
PAINT SKYBLUE (6150 1975);
FORCEPROP 1 LAST TOLERANCE 20%
J 0
(6150 2025);
DISPLAY 0.617021 (6150 2025);
PAINT SKYBLUE (6150 2025);
FORCEPROP 1 LAST VOLTAGE 6.3V
J 0
(6150 2075);
DISPLAY 0.617021 (6150 2075);
PAINT SKYBLUE (6150 2075);
FORCEPROP 1 LAST PACK_TYPE 0603
J 0
(6150 1875);
DISPLAY 0.617021 (6150 1875);
PAINT SKYBLUE (6150 1875);
FORCEPROP 1 LASTPIN (6100 2175) $PN 1
J 0
(6110 2155);
DISPLAY 0.787234 (6110 2155);
PAINT ORANGE (6110 2155);
DISPLAY INVISIBLE (6110 2155);
FORCEPROP 1 LASTPIN (6100 1975) $PN 2
J 0
(6110 1955);
DISPLAY 0.787234 (6110 1955);
PAINT ORANGE (6110 1955);
DISPLAY INVISIBLE (6110 1955);
FORCEPROP 2 LAST BOM_COST P1V538_BMC_STBY_VR
J 0
(5975 2225);
PAINT WHITE (5975 2225);
DISPLAY INVISIBLE (5975 2225);
FORCEPROP 2 LAST ROOM P1V538_BMC_STBY_VR
J 0
(6150 2225);
DISPLAY 0.723404 (6150 2225);
PAINT GREEN (6150 2225);
DISPLAY INVISIBLE (6150 2225);
FORCEPROP 1 LAST PATH I92
J 0
(6150 2225);
DISPLAY 0.978723 (6150 2225);
PAINT WHITE (6150 2225);
DISPLAY INVISIBLE (6150 2225);
FORCEPROP 2 LAST CDS_LIB mstr_discrete
J 0
(6100 2075);
PAINT MONO (6100 2075);
DISPLAY INVISIBLE (6100 2075);
FORCEADD GND..1
(6100 1775);
FORCEPROP 3 LASTPIN (6100 1825) SIG_NAME GND\g
J 0
(6110 1835);
DISPLAY 0.659574 (6110 1835);
PAINT MONO (6110 1835);
DISPLAY INVISIBLE (6110 1835);
FORCEPROP 1 LAST VOLTAGE 0.0V
J 0
(6055 1732);
DISPLAY 0.340426 (6055 1732);
PAINT SKYBLUE (6055 1732);
DISPLAY INVISIBLE (6055 1732);
FORCEPROP 1 LAST SIZE 1B
J 0
(6175 1725);
DISPLAY 0.872340 (6175 1725);
PAINT AQUA (6175 1725);
DISPLAY INVISIBLE (6175 1725);
FORCEPROP 1 LAST PATH I93
J 0
(6175 1775);
DISPLAY 0.872340 (6175 1775);
PAINT AQUA (6175 1775);
DISPLAY INVISIBLE (6175 1775);
FORCEPROP 2 LAST CDS_LIB mstr_symbols
J 0
(6100 1775);
PAINT MONO (6100 1775);
DISPLAY INVISIBLE (6100 1775);
FORCEPROP 1 LAST BODY_TYPE PLUMBING
J 0
(6055 1732);
DISPLAY 0.340426 (6055 1732);
PAINT GREEN (6055 1732);
DISPLAY INVISIBLE (6055 1732);
FORCEPROP 1 LAST HDL_POWER GND
J 0
(6100 1925);
DISPLAY 0.872340 (6100 1925);
PAINT GREEN (6100 1925);
DISPLAY INVISIBLE (6100 1925);
FORCEADD OFFPAGE..1
(5950 1500);
FORCEPROP 2 LAST ROOM P1V538_BMC_STBY_VR
J 0
(5475 1575);
DISPLAY 1.340426 (5475 1575);
PAINT GREEN (5475 1575);
DISPLAY INVISIBLE (5475 1575);
FORCEPROP 2 LAST BOM_COST P1V538_BMC_STBY_VR
J 0
(5675 1550);
PAINT WHITE (5675 1550);
DISPLAY INVISIBLE (5675 1550);
FORCEPROP 2 LAST PATH I94
J 0
(6000 1575);
DISPLAY 1.021277 (6000 1575);
PAINT ORANGE (6000 1575);
DISPLAY INVISIBLE (6000 1575);
FORCEPROP 2 LAST CDS_LIB mstr_standard
J 0
(5950 1500);
PAINT MONO (5950 1500);
DISPLAY INVISIBLE (5950 1500);
FORCEPROP 1 LAST OFFPAGE TRUE
J 0
(6275 1375);
PAINT GREEN (6275 1375);
DISPLAY INVISIBLE (6275 1375);
FORCEPROP 1 LAST COMMENT_BODY TRUE
J 0
(6075 1400);
DISPLAY 1.170213 (6075 1400);
PAINT PEACH (6075 1400);
DISPLAY INVISIBLE (6075 1400);
FORCEADD GND..1
(6625 800);
FORCEPROP 3 LASTPIN (6625 850) SIG_NAME GND\g
J 0
(6635 860);
DISPLAY 0.659574 (6635 860);
PAINT MONO (6635 860);
DISPLAY INVISIBLE (6635 860);
FORCEPROP 2 LAST P1V5_STBY_IBMC_VR 
J 0
(6650 875);
PAINT GREEN (6650 875);
FORCEPROP 2 LAST P1V5_STBY_IBMC 
J 0
(6650 925);
PAINT GREEN (6650 925);
FORCEPROP 2 LAST ROOM P1V538_BMC_STBY_VR
J 0
(6275 875);
DISPLAY 0.872340 (6275 875);
PAINT GREEN (6275 875);
DISPLAY INVISIBLE (6275 875);
FORCEPROP 1 LAST SIZE 1B
J 0
(6700 750);
DISPLAY 0.872340 (6700 750);
PAINT ORANGE (6700 750);
DISPLAY INVISIBLE (6700 750);
FORCEPROP 1 LAST VOLTAGE 0.0V
J 0
(6580 757);
DISPLAY 0.340426 (6580 757);
PAINT SKYBLUE (6580 757);
DISPLAY INVISIBLE (6580 757);
FORCEPROP 2 LAST BOM_COST P1V538_BMC_STBY_VR
J 0
(6650 975);
PAINT WHITE (6650 975);
DISPLAY INVISIBLE (6650 975);
FORCEPROP 1 LAST PATH I95
J 0
(6700 800);
DISPLAY 0.872340 (6700 800);
PAINT AQUA (6700 800);
DISPLAY INVISIBLE (6700 800);
FORCEPROP 2 LAST CDS_LIB mstr_symbols
J 0
(6625 800);
PAINT MONO (6625 800);
DISPLAY INVISIBLE (6625 800);
FORCEPROP 1 LAST BODY_TYPE PLUMBING
J 0
(6580 757);
DISPLAY 0.340426 (6580 757);
PAINT GREEN (6580 757);
DISPLAY INVISIBLE (6580 757);
FORCEPROP 1 LAST HDL_POWER GND
J 0
(6625 950);
DISPLAY 0.872340 (6625 950);
PAINT GREEN (6625 950);
DISPLAY INVISIBLE (6625 950);
FORCEADD W_VCC_CIRCLE..1
(11300 1900);
FORCEPROP 3 LASTPIN (11300 1900) SIG_NAME P2V5_AUX_BMC\g
J 0
(11310 1910);
DISPLAY 0.659574 (11310 1910);
PAINT MONO (11310 1910);
DISPLAY INVISIBLE (11310 1910);
FORCEPROP 1 LAST HDL_POWER P2V5_AUX_BMC
J 1
(11321 1975);
DISPLAY 0.872340 (11321 1975);
PAINT ORANGE (11321 1975);
FORCEPROP 2 LAST CDS_LIB w_power
J 0
(11300 1900);
PAINT MONO (11300 1900);
DISPLAY INVISIBLE (11300 1900);
FORCEPROP 1 LAST PATH I96
J 0
(11300 1900);
DISPLAY 0.617021 (11300 1900);
PAINT GREEN (11300 1900);
DISPLAY INVISIBLE (11300 1900);
FORCEPROP 1 LAST CDS_LMAN_SYM_OUTLINE -100,100,100,-100
J 0
(11300 1900);
DISPLAY 0.468085 (11300 1900);
PAINT GREEN (11300 1900);
DISPLAY INVISIBLE (11300 1900);
FORCEPROP 1 LAST BODY_TYPE PLUMBING
J 0
(11312 1894);
DISPLAY 0.340426 (11312 1894);
PAINT GREEN (11312 1894);
DISPLAY INVISIBLE (11312 1894);
FORCEADD W_VCC_CIRCLE..1
(11725 3975);
FORCEPROP 3 LASTPIN (11725 3975) SIG_NAME P1V2_AUX_BMC\g
J 0
(11735 3985);
DISPLAY 0.659574 (11735 3985);
PAINT MONO (11735 3985);
DISPLAY INVISIBLE (11735 3985);
FORCEPROP 1 LAST HDL_POWER P1V2_AUX_BMC
J 1
(11746 4050);
DISPLAY 0.872340 (11746 4050);
PAINT ORANGE (11746 4050);
FORCEPROP 1 LAST CDS_LMAN_SYM_OUTLINE -100,100,100,-100
J 0
(11725 3975);
DISPLAY 0.468085 (11725 3975);
PAINT GREEN (11725 3975);
DISPLAY INVISIBLE (11725 3975);
FORCEPROP 1 LAST PATH I97
J 0
(11725 3975);
DISPLAY 0.617021 (11725 3975);
PAINT GREEN (11725 3975);
DISPLAY INVISIBLE (11725 3975);
FORCEPROP 2 LAST CDS_LIB w_power
J 0
(11725 3975);
PAINT MONO (11725 3975);
DISPLAY INVISIBLE (11725 3975);
FORCEPROP 1 LAST BODY_TYPE PLUMBING
J 0
(11737 3969);
DISPLAY 0.340426 (11737 3969);
PAINT GREEN (11737 3969);
DISPLAY INVISIBLE (11737 3969);
FORCEADD 5K1R2F-2-GP..1
(10350 3525);
FORCEPROP 1 LAST VALUE 5K1R2F-2-GP
J 0
(10375 3425);
DISPLAY 0.617021 (10375 3425);
PAINT GREEN (10375 3425);
FORCEPROP 1 LAST LOCATION R9F31
J 0
(10375 3605);
DISPLAY 0.617021 (10375 3605);
PAINT GREEN (10375 3605);
FORCEPROP 1 LAST PACK_TYPE SMD-RG
J 0
(10350 3525);
DISPLAY 0.617021 (10350 3525);
PAINT GREEN (10350 3525);
DISPLAY INVISIBLE (10350 3525);
FORCEPROP 1 LAST PART_NUMBER 64.51015.6DL
J 0
(10350 3525);
DISPLAY 0.617021 (10350 3525);
PAINT GREEN (10350 3525);
DISPLAY INVISIBLE (10350 3525);
FORCEPROP 2 LAST CDS_LIB w_hdl
J 0
(10350 3525);
PAINT MONO (10350 3525);
DISPLAY INVISIBLE (10350 3525);
FORCEPROP 1 LAST PATH I98
J 0
(10350 3525);
DISPLAY 0.617021 (10350 3525);
PAINT GREEN (10350 3525);
DISPLAY INVISIBLE (10350 3525);
FORCEPROP 1 LAST CDS_LMAN_SYM_OUTLINE -50,75,50,-75
J 0
(10350 3525);
DISPLAY 0.468085 (10350 3525);
PAINT GREEN (10350 3525);
DISPLAY INVISIBLE (10350 3525);
FORCEADD 21K5R2F-GP..1
(9925 1325);
FORCEPROP 1 LAST LOCATION R9W31
J 0
(9950 1405);
DISPLAY 0.617021 (9950 1405);
PAINT GREEN (9950 1405);
FORCEPROP 1 LAST VALUE 21K5R2F-GP
J 0
(9950 1220);
DISPLAY 0.617021 (9950 1220);
PAINT GREEN (9950 1220);
FORCEPROP 1 LAST PACK_TYPE RCL_GP
J 0
(9925 1325);
DISPLAY 0.617021 (9925 1325);
PAINT GREEN (9925 1325);
DISPLAY INVISIBLE (9925 1325);
FORCEPROP 1 LAST PART_NUMBER 64.21525.6DL
J 0
(9925 1325);
DISPLAY 0.617021 (9925 1325);
PAINT GREEN (9925 1325);
DISPLAY INVISIBLE (9925 1325);
FORCEPROP 2 LAST CDS_LIB w_hdl
J 0
(9925 1325);
PAINT MONO (9925 1325);
DISPLAY INVISIBLE (9925 1325);
FORCEPROP 1 LAST PATH I99
J 0
(9925 1325);
DISPLAY 0.617021 (9925 1325);
PAINT GREEN (9925 1325);
DISPLAY INVISIBLE (9925 1325);
FORCEPROP 1 LAST CDS_LMAN_SYM_OUTLINE -50,75,50,-75
J 0
(9925 1325);
DISPLAY 0.468085 (9925 1325);
PAINT GREEN (9925 1325);
DISPLAY INVISIBLE (9925 1325);
FORCEPROP 2 LASTPIN (9925 1200) SIG_NAME UN$239$21K5R2F-GP$I99$2
J 0
(9935 1210);
DISPLAY 0.659574 (9935 1210);
PAINT MONO (9935 1210);
DISPLAY INVISIBLE (9935 1210);
FORCEADD INTEL_CORP_BPAGE..1
(13000 200);
FORCEPROP 1 LAST CDS_CON_LAST_MODIFIED Tue Dec 01 15:03:21 2015
J 0
(11575 525);
PAINT ORANGE (11575 525);
DISPLAY INVISIBLE (11575 525);
FORCEPROP 1 LAST CUSTOM_TXT_CDS <CURRENT_DESIGN_SHEET> OF <TOTAL_DESIGN_SHEETS>
J 0
(12500 225);
PAINT ORANGE (12500 225);
FORCEPROP 1 LAST CUSTOM_TXT_CDS <CON_LAST_MODIFIED>
J 0
(11075 550);
PAINT ORANGE (11075 550);
FORCEPROP 2 LAST CUSTOM_TXT_CDS <XR_PAGE_TITLE>
J 0
(5110 5450);
DISPLAY 0.638298 (5110 5450);
PAINT PINK (5110 5450);
DISPLAY INVISIBLE (5110 5450);
FORCEPROP 1 LAST SCH_TITLE P1V2 & P2V5 BMC STBY VR
J 0
(5050 250);
DISPLAY 1.212766 (5050 250);
PAINT ORANGE (5050 250);
FORCEPROP 1 LAST SCH_REV 2.420
J 0
(12750 350);
DISPLAY 0.978723 (12750 350);
PAINT YELLOW (12750 350);
FORCEPROP 1 LAST SCH_DEPT BESD
J 1
(8550 300);
DISPLAY 1.212766 (8550 300);
PAINT YELLOW (8550 300);
FORCEPROP 1 LAST SCH_ADDRESS2 P.O. BOX 58119
J 0
(9025 275);
DISPLAY 0.617021 (9025 275);
PAINT GREEN (9025 275);
FORCEPROP 1 LAST SCH_NUMBER H4694802
J 0
(11700 350);
DISPLAY 1.212766 (11700 350);
PAINT YELLOW (11700 350);
FORCEPROP 1 LAST SCH_ADDRESS3 Santa Clara, CA 95052-8119
J 0
(9025 225);
DISPLAY 0.617021 (9025 225);
PAINT GREEN (9025 225);
FORCEPROP 1 LAST SCH_ADDRESS1 2200 Mission College Blvd.
J 0
(9025 325);
DISPLAY 0.617021 (9025 325);
PAINT GREEN (9025 325);
FORCEPROP 2 LAST CDS_XR_PAGE_TITLE CR-239 : @BASEBOARD_FAB2_LIB.BASEBOARD_FAB2(SCH_1):PAGE239
J 0
(5110 5450);
DISPLAY 0.638298 (5110 5450);
PAINT PINK (5110 5450);
DISPLAY INVISIBLE (5110 5450);
FORCEPROP 2 LAST CDS_LIB mstr_symbols
J 0
(13000 200);
PAINT MONO (13000 200);
DISPLAY INVISIBLE (13000 200);
FORCEPROP 2 LAST PAGE_BORDER TRUE
J 0
(5110 5450);
DISPLAY 0.851064 (5110 5450);
PAINT PINK (5110 5450);
DISPLAY INVISIBLE (5110 5450);
FORCEPROP 1 LAST COMMENT_BODY TRUE
J 0
(13012 212);
DISPLAY 0.446809 (13012 212);
PAINT GREEN (13012 212);
DISPLAY INVISIBLE (13012 212);
FORCEADD DESIGN_NOTE..1
(11850 4875);
FORCEPROP 2 LAST CDS_LIB mstr_symbols
J 0
(11850 4875);
PAINT ORANGE (11850 4875);
DISPLAY INVISIBLE (11850 4875);
FORCEPROP 1 LAST COMMENT_BODY TRUE
J 0
(11875 4975);
DISPLAY 1.361702 (11875 4975);
PAINT WHITE (11875 4975);
DISPLAY INVISIBLE (11875 4975);
FORCEADD CAD_NOTE..1
(6850 4225);
FORCEPROP 0 LAST L1 MUST PLACE
J 0
(6700 4125);
DISPLAY 0.744681 (6700 4125);
PAINT WHITE (6700 4125);
FORCEPROP 0 LAST L2 NEXT TO INPUT PIN
J 0
(6700 4075);
DISPLAY 0.744681 (6700 4075);
PAINT WHITE (6700 4075);
FORCEPROP 2 LAST CDS_LIB mstr_symbols
J 0
(6850 4225);
DISPLAY 1.617021 (6850 4225);
PAINT WHITE (6850 4225);
DISPLAY INVISIBLE (6850 4225);
FORCEPROP 2 LAST ROOM P1V538_BMC_STBY_VR
J 0
(6700 4175);
DISPLAY 1.659574 (6700 4175);
PAINT GREEN (6700 4175);
DISPLAY INVISIBLE (6700 4175);
FORCEPROP 1 LAST COMMENT_BODY TRUE
J 0
(6875 4325);
DISPLAY 2.212766 (6875 4325);
PAINT PEACH (6875 4325);
DISPLAY INVISIBLE (6875 4325);
FORCEADD DESIGN_NOTE..1
(11450 2650);
FORCEPROP 2 LAST CDS_LIB mstr_symbols
J 0
(11450 2650);
PAINT MONO (11450 2650);
DISPLAY INVISIBLE (11450 2650);
FORCEPROP 1 LAST COMMENT_BODY TRUE
J 0
(11475 2750);
DISPLAY 1.361702 (11475 2750);
PAINT WHITE (11475 2750);
DISPLAY INVISIBLE (11475 2750);
FORCEADD DNS..2
(6630 1220);
PAINT RED (6630 1220);
FORCEPROP 2 LAST CDS_LIB mstr_misc
J 0
(6630 1220);
PAINT MONO (6630 1220);
DISPLAY INVISIBLE (6630 1220);
FORCEPROP 1 LAST COMMENT_BODY TRUE
R 1
J 0
(6705 995);
DISPLAY 0.872340 (6705 995);
PAINT GREEN (6705 995);
DISPLAY INVISIBLE (6705 995);
FORCEADD CAD_NOTE..1
(6425 2150);
FORCEPROP 0 LAST L2 NEXT TO INPUT PIN
J 0
(6275 2000);
DISPLAY 0.744681 (6275 2000);
PAINT WHITE (6275 2000);
FORCEPROP 0 LAST L1 MUST PLACE
J 0
(6275 2050);
DISPLAY 0.744681 (6275 2050);
PAINT WHITE (6275 2050);
FORCEPROP 2 LAST ROOM P1V538_BMC_STBY_VR
J 0
(6275 2100);
DISPLAY 1.659574 (6275 2100);
PAINT GREEN (6275 2100);
DISPLAY INVISIBLE (6275 2100);
FORCEPROP 2 LAST CDS_LIB mstr_symbols
J 0
(6425 2150);
PAINT MONO (6425 2150);
DISPLAY INVISIBLE (6425 2150);
FORCEPROP 1 LAST COMMENT_BODY TRUE
J 0
(6450 2250);
DISPLAY 2.212766 (6450 2250);
PAINT PEACH (6450 2250);
DISPLAY INVISIBLE (6450 2250);
FORCEADD DNS..2
(7055 3295);
PAINT RED (7055 3295);
FORCEPROP 2 LAST CDS_LIB mstr_misc
J 0
(7055 3295);
PAINT ORANGE (7055 3295);
DISPLAY INVISIBLE (7055 3295);
FORCEPROP 1 LAST COMMENT_BODY TRUE
R 1
J 0
(7130 3070);
DISPLAY 0.872340 (7130 3070);
PAINT GREEN (7130 3070);
DISPLAY INVISIBLE (7130 3070);
WIRE 16 -1 (10350 3025)(10350 2950);
WIRE 16 -1 (9625 4950)(9625 4625);
WIRE 16 -1 (7050 3200)(7050 2925);
WIRE 16 -1 (6525 3900)(6525 4050);
WIRE 16 -1 (10375 4025)(10375 4050);
WIRE 16 -1 (9450 3400)(9450 3475);
WIRE 16 -1 (9350 3475)(9450 3475);
WIRE 16 -1 (6525 4575)(6525 4425);
WIRE 16 -1 (6525 4425)(7475 4425);
WIRE 16 -1 (6525 4425)(6525 4250);
WIRE 16 -1 (7475 4425)(8050 4425);
WIRE 16 -1 (7475 4225)(7475 4425);
WIRE 16 -1 (8050 4425)(8050 3975);
WIRE 16 -1 (8050 3975)(8050 3825);
WIRE 16 -1 (8050 3975)(8350 3975);
WIRE 16 -1 (8225 3825)(8050 3825);
WIRE 16 -1 (8225 3775)(8225 3825);
WIRE 16 -1 (8350 3825)(8225 3825);
WIRE 16 -1 (8225 3725)(8225 3775);
WIRE 16 -1 (8350 3775)(8225 3775);
WIRE 16 -1 (8350 3725)(8225 3725);
WIRE 16 -1 (7475 4025)(7475 3900);
WIRE 16 -1 (7050 1950)(7050 1825);
WIRE 16 -1 (6100 2500)(6100 2350);
WIRE 16 -1 (6100 2350)(7050 2350);
WIRE 16 -1 (6100 2350)(6100 2175);
WIRE 16 -1 (7050 2350)(7625 2350);
WIRE 16 -1 (7050 2150)(7050 2350);
WIRE 16 -1 (7625 2350)(7625 1900);
WIRE 16 -1 (7625 1900)(7625 1750);
WIRE 16 -1 (7625 1900)(7925 1900);
WIRE 16 -1 (7800 1750)(7625 1750);
WIRE 16 -1 (7800 1700)(7800 1750);
WIRE 16 -1 (7925 1750)(7800 1750);
WIRE 16 -1 (7800 1650)(7800 1700);
WIRE 16 -1 (7925 1700)(7800 1700);
WIRE 16 -1 (7925 1650)(7800 1650);
WIRE 16 -1 (9200 2650)(9200 2550);
WIRE 16 -1 (10750 1175)(10750 1250);
WIRE 16 -1 (10750 1250)(10875 1250);
WIRE 16 -1 (10450 1250)(10750 1250);
WIRE 16 -1 (10450 1250)(10450 1450);
WIRE 16 -1 (10875 1375)(10875 1250);
WIRE 16 -1 (9950 1950)(9950 1975);
WIRE 16 -1 (9925 800)(9925 675);
WIRE 16 -1 (11175 3250)(11175 3325);
WIRE 16 -1 (10875 3325)(11175 3325);
WIRE 16 -1 (11175 3325)(11300 3325);
WIRE 16 -1 (11300 3450)(11300 3325);
WIRE 16 -1 (10875 3325)(10875 3525);
WIRE 16 -1 (6100 1825)(6100 1975);
WIRE 16 -1 (6625 1125)(6625 850);
WIRE 16 -1 (11300 1900)(11300 1750);
WIRE 16 -1 (10875 1750)(11300 1750);
WIRE 16 -1 (10450 1750)(10875 1750);
WIRE 16 -1 (10875 1575)(10875 1750);
WIRE 16 -1 (9925 1750)(10450 1750);
WIRE 16 -1 (10450 1750)(10450 1650);
WIRE 16 -1 (9000 1750)(9925 1750);
WIRE 16 -1 (9925 1450)(9925 1750);
WIRE 16 -1 (9000 1700)(9000 1750);
WIRE 16 -1 (8925 1750)(9000 1750);
WIRE 16 -1 (9000 1650)(9000 1700);
WIRE 16 -1 (8925 1700)(9000 1700);
WIRE 16 -1 (8925 1650)(9000 1650);
WIRE 16 -1 (11725 3975)(11725 3825);
WIRE 16 -1 (11300 3825)(11725 3825);
WIRE 16 -1 (10875 3825)(11300 3825);
FORCEPROP 0 LAST VOLTAGE 1.5
J 0
(11125 3875);
PAINT SKYBLUE (11125 3875);
DISPLAY INVISIBLE (11125 3875);
WIRE 16 -1 (11300 3650)(11300 3825);
WIRE 16 -1 (10350 3825)(10875 3825);
WIRE 16 -1 (10875 3825)(10875 3725);
WIRE 16 -1 (9425 3825)(10350 3825);
WIRE 16 -1 (10350 3650)(10350 3825);
WIRE 16 -1 (9425 3775)(9425 3825);
WIRE 16 -1 (9350 3825)(9425 3825);
WIRE 16 -1 (9425 3725)(9425 3775);
WIRE 16 -1 (9350 3775)(9425 3775);
WIRE 16 -1 (9350 3725)(9425 3725);
WIRE 16 -1 (9025 1325)(9025 1400);
WIRE 16 -1 (8925 1400)(9025 1400);
WIRE 16 -1 (6000 1500)(6625 1500);
FORCEPROP 2 LAST SIG_NAME PWRGD_P3V3_STBY
J 0
(6040 1510);
DISPLAY 0.617021 (6040 1510);
PAINT ORANGE (6040 1510);
WIRE 16 -1 (6625 1325)(6625 1500);
WIRE 16 -1 (6625 1500)(7925 1500);
WIRE 16 -1 (8925 1900)(9200 1900);
WIRE 16 -1 (9200 1900)(9200 2200);
WIRE 16 -1 (9200 2350)(9200 2200);
WIRE 16 -1 (9950 2175)(9950 2200);
WIRE 16 -1 (10175 2200)(9950 2200);
WIRE 16 -1 (9950 2200)(9200 2200);
WIRE 3 2175 (5275 2825)(5275 525);
WIRE 3 2175 (5275 525)(11975 525);
WIRE 3 2175 (5275 2825)(11975 2825);
WIRE 3 2175 (11975 2825)(11975 525);
WIRE 3 2175 (9625 1025)(10300 1025);
WIRE 3 2175 (10300 1600)(10300 1025);
WIRE 3 2175 (9625 1600)(9625 1025);
WIRE 3 2175 (9625 1600)(10300 1600);
WIRE 16 -1 (9925 1000)(9925 1100);
WIRE 16 -1 (9925 1100)(9925 1200);
WIRE 16 -1 (9650 1100)(9925 1100);
WIRE 16 -1 (9650 1500)(9650 1100);
WIRE 16 -1 (8925 1500)(9650 1500);
WIRE 3 2175 (10250 3725)(10800 3725);
WIRE 3 2175 (10800 3725)(10800 3300);
WIRE 3 2175 (10250 3725)(10250 3300);
WIRE 3 2175 (10250 3300)(10800 3300);
WIRE 3 2175 (11500 3750)(12050 3750);
WIRE 3 2175 (12050 4175)(12050 3750);
WIRE 3 2175 (11500 4175)(11500 3750);
WIRE 3 2175 (11500 4175)(12050 4175);
WIRE 16 -1 (11075 2200)(10375 2200);
WIRE 16 -1 (9350 3575)(10075 3575);
FORCEPROP 2 LAST SIG_NAME VR_P1V538_BMC_STBY_FB
J 0
(9541 3585);
DISPLAY 0.617021 (9541 3585);
PAINT ORANGE (9541 3585);
FORCEPROP 2 LASTPROP $XRERR UNIQUE?
J 0
(9301 3585);
DISPLAY 0.638298 (9301 3585);
PAINT MONO (9301 3585);
DISPLAY INVISIBLE (9301 3585);
WIRE 16 -1 (10075 3575)(10075 3325);
WIRE 16 -1 (10075 3325)(10350 3325);
WIRE 16 -1 (10350 3325)(10350 3400);
WIRE 16 -1 (10350 3225)(10350 3325);
WIRE 16 -1 (6425 3575)(7050 3575);
FORCEPROP 2 LAST SIG_NAME PWRGD_P3V3_STBY
J 0
(6466 3585);
DISPLAY 0.617021 (6466 3585);
PAINT ORANGE (6466 3585);
WIRE 16 -1 (7050 3575)(8350 3575);
WIRE 16 -1 (7050 3400)(7050 3575);
WIRE 16 -1 (10375 4250)(10375 4275);
WIRE 16 -1 (10600 4275)(10375 4275);
WIRE 16 -1 (9625 4425)(9625 4275);
WIRE 16 -1 (10375 4275)(9625 4275);
FORCEPROP 2 LAST SIG_NAME PWRGD_P1V538_BMC_STBY_R
J 0
(9741 4285);
DISPLAY 0.617021 (9741 4285);
PAINT ORANGE (9741 4285);
FORCEPROP 2 LASTPROP $XRERR UNIQUE?
J 0
(9501 4285);
DISPLAY 0.638298 (9501 4285);
PAINT MONO (9501 4285);
DISPLAY INVISIBLE (9501 4285);
WIRE 16 -1 (9625 3975)(9625 4275);
WIRE 16 -1 (9350 3975)(9625 3975);
WIRE 16 -1 (11500 4275)(10800 4275);
FORCEPROP 2 LAST SIG_NAME PWRGD_P1V538_BMC_STBY
J 0
(10866 4285);
DISPLAY 0.617021 (10866 4285);
PAINT ORANGE (10866 4285);
DOT 1 (10750 1250);
DOT 1 (9925 1100);
DOT 1 (7625 1900);
DOT 1 (6100 2350);
DOT 1 (9950 2200);
DOT 1 (9200 2200);
DOT 1 (9925 1750);
DOT 1 (9000 1750);
DOT 1 (7050 2350);
DOT 1 (6625 1500);
DOT 1 (7050 3575);
DOT 1 (8050 3975);
DOT 1 (6525 4425);
DOT 1 (7475 4425);
DOT 1 (8225 3775);
DOT 1 (8225 3825);
DOT 1 (9425 3775);
DOT 1 (9425 3825);
DOT 1 (10350 3825);
DOT 1 (11175 3325);
DOT 1 (10875 3825);
DOT 1 (11300 3825);
DOT 1 (9625 4275);
DOT 1 (10375 4275);
DOT 1 (7800 1750);
DOT 1 (7800 1700);
DOT 1 (10350 3325);
DOT 1 (9000 1700);
DOT 1 (10875 1750);
DOT 1 (10450 1750);
FORCENOTE
TP FAB1 CHANGE POWER RAIL 1120
(11525 3625) 0;
DISPLAY LEFT (11525 3625);
DISPLAY 1.021277 (11525 3625);
PAINT RED (11525 3625);
FORCENOTE
IOUT=1.192A
(11650 4650) 0;
DISPLAY LEFT (11650 4650);
DISPLAY 1.021277 (11650 4650);
PAINT PURPLE (11650 4650);
FORCENOTE
TP FAB1 CHANGE VALUE FOR 1.2V
(9275 3200) 0;
DISPLAY LEFT (9275 3200);
DISPLAY 1.021277 (9275 3200);
PAINT RED (9275 3200);
FORCENOTE
TP FAB1 ADD P2V5 FOR DDR4 1120
(9675 2725) 0;
DISPLAY LEFT (9675 2725);
DISPLAY 1.021277 (9675 2725);
PAINT RED (9675 2725);
FORCENOTE
TP FAB1 R9W31 CHANGE TO 21.5K 1123
(10175 925) 0;
DISPLAY LEFT (10175 925);
DISPLAY 1.021277 (10175 925);
PAINT RED (10175 925);
FORCENOTE
IOUT=1.192A
(11275 2400) 0;
DISPLAY LEFT (11275 2400);
DISPLAY 1.021277 (11275 2400);
PAINT PURPLE (11275 2400);
FORCENOTE
VOUT=1.538V
(11650 4725) 0;
DISPLAY LEFT (11650 4725);
DISPLAY 1.021277 (11650 4725);
PAINT PURPLE (11650 4725);
FORCENOTE
VOUT=2.5V
(11250 2475) 0;
DISPLAY LEFT (11250 2475);
DISPLAY 1.021277 (11250 2475);
PAINT PURPLE (11250 2475);
QUIT
